FILE_TYPE = MACRO_DRAWING;
SET COLOR_WIRE YELLOW;
SET COLOR_PROP ORANGE;
SET COLOR_DOT WHITE;
SET COLOR_ARC YELLOW;
SET COLOR_BODY GREEN;
SET COLOR_NOTE PURPLE;
SET PROP_DISPLAY VALUE;
SET PAGE_NUMBER P157;
FORCEADD TUSB8042AIRGCR..2
(-4400 4500);
FORCEPROP 1 LAST LOCATION U6002
J 0
(-4970 6211);
DISPLAY 0.723404 (-4970 6211);
PAINT GREEN (-4970 6211);
FORCEPROP 2 LAST SEC 2
J 0
(-4950 6350);
DISPLAY 0.680851 (-4950 6350);
PAINT MONO (-4950 6350);
DISPLAY INVISIBLE (-4950 6350);
FORCEPROP 2 LASTPIN (-5125 4925) $PN 45
J 2
(-5135 4935);
DISPLAY 0.680851 (-5135 4935);
PAINT MONO (-5135 4935);
FORCEPROP 2 LASTPIN (-5125 4325) $PN 40
J 2
(-5135 4335);
DISPLAY 0.680851 (-5135 4335);
PAINT MONO (-5135 4335);
FORCEPROP 2 LASTPIN (-5125 4625) $PN 42
J 2
(-5135 4635);
DISPLAY 0.680851 (-5135 4635);
PAINT MONO (-5135 4635);
FORCEPROP 2 LASTPIN (-5125 5275) $PN 38
R 1
J 0
(-5135 5285);
DISPLAY 0.680851 (-5135 5285);
PAINT MONO (-5135 5285);
FORCEPROP 2 LASTPIN (-5125 5475) $PN 37
J 2
(-5135 5485);
DISPLAY 0.680851 (-5135 5485);
PAINT MONO (-5135 5485);
FORCEPROP 2 LASTPIN (-5125 5675) $PN 39
J 2
(-5135 5685);
DISPLAY 0.680851 (-5135 5685);
PAINT MONO (-5135 5685);
FORCEPROP 2 LASTPIN (-3675 3875) $PN 16
J 0
(-3665 3885);
DISPLAY 0.680851 (-3665 3885);
PAINT MONO (-3665 3885);
FORCEPROP 2 LASTPIN (-3675 3725) $PN 34
J 0
(-3665 3735);
DISPLAY 0.680851 (-3665 3735);
PAINT MONO (-3665 3735);
FORCEPROP 2 LASTPIN (-3675 3575) $PN 52
J 0
(-3665 3585);
DISPLAY 0.680851 (-3665 3585);
PAINT MONO (-3665 3585);
FORCEPROP 2 LASTPIN (-3675 3425) $PN 63
J 0
(-3665 3435);
DISPLAY 0.680851 (-3665 3435);
PAINT MONO (-3665 3435);
FORCEPROP 2 LASTPIN (-3675 5675) $PN 5
J 0
(-3665 5685);
DISPLAY 0.680851 (-3665 5685);
PAINT MONO (-3665 5685);
FORCEPROP 2 LASTPIN (-3675 5525) $PN 8
J 0
(-3665 5535);
DISPLAY 0.680851 (-3665 5535);
PAINT MONO (-3665 5535);
FORCEPROP 2 LASTPIN (-3675 5375) $PN 13
J 0
(-3665 5385);
DISPLAY 0.680851 (-3665 5385);
PAINT MONO (-3665 5385);
FORCEPROP 2 LASTPIN (-3675 5225) $PN 21
J 0
(-3665 5235);
DISPLAY 0.680851 (-3665 5235);
PAINT MONO (-3665 5235);
FORCEPROP 2 LASTPIN (-3675 5075) $PN 28
J 0
(-3665 5085);
DISPLAY 0.680851 (-3665 5085);
PAINT MONO (-3665 5085);
FORCEPROP 2 LASTPIN (-3675 4925) $PN 31
J 0
(-3665 4935);
DISPLAY 0.680851 (-3665 4935);
PAINT MONO (-3665 4935);
FORCEPROP 2 LASTPIN (-3675 4775) $PN 51
J 0
(-3665 4785);
DISPLAY 0.680851 (-3665 4785);
PAINT MONO (-3665 4785);
FORCEPROP 2 LASTPIN (-3675 4625) $PN 57
J 0
(-3665 4635);
DISPLAY 0.680851 (-3665 4635);
PAINT MONO (-3665 4635);
FORCEPROP 2 LASTPIN (-5125 3475) $PN 62
R 1
J 2
(-5135 3465);
DISPLAY 0.680851 (-5135 3465);
PAINT MONO (-5135 3465);
FORCEPROP 2 LASTPIN (-5125 3725) $PN 61
J 2
(-5135 3735);
DISPLAY 0.680851 (-5135 3735);
PAINT MONO (-5135 3735);
FORCEPROP 0 LAST ROOM USB3_HUB2
J 0
(-4950 6400);
DISPLAY 0.680851 (-4950 6400);
PAINT RED (-4950 6400);
FORCEPROP 2 LAST VALUE TUSB8042AIRGCR
J 0
(-4950 6250);
DISPLAY 0.680851 (-4950 6250);
FORCEPROP 1 LAST MATERIAL IC
J 0
(-4970 5937);
DISPLAY 0.723404 (-4970 5937);
PAINT GREEN (-4970 5937);
FORCEPROP 2 LAST PART_TYPE SMLF
J 0
(-4950 6300);
DISPLAY 0.680851 (-4950 6300);
FORCEPROP 2 LAST SEC_TYPE 
J 0
(-4950 6350);
DISPLAY 0.680851 (-4950 6350);
DISPLAY INVISIBLE (-4950 6350);
FORCEPROP 2 LAST CDS_LIB pure_quanta
J 0
(-4400 4500);
DISPLAY INVISIBLE (-4400 4500);
FORCEPROP 1 LAST NEEDS_NO_SIZE TRUE
J 0
(-4400 4500);
DISPLAY 0.723404 (-4400 4500);
PAINT GREEN (-4400 4500);
DISPLAY INVISIBLE (-4400 4500);
FORCEPROP 1 LAST CDS_LMAN_SYM_OUTLINE -575,1425,575,-1425
J 0
(-4400 4500);
DISPLAY 0.468085 (-4400 4500);
PAINT GREEN (-4400 4500);
DISPLAY INVISIBLE (-4400 4500);
FORCEPROP 1 LAST PATH I119
J 0
(-4400 4500);
DISPLAY 0.723404 (-4400 4500);
PAINT GREEN (-4400 4500);
DISPLAY INVISIBLE (-4400 4500);
FORCEPROP 1 LAST PART_NUMBER AL008042000
J 0
(-4970 6064);
DISPLAY 0.723404 (-4970 6064);
PAINT GREEN (-4970 6064);
DISPLAY INVISIBLE (-4970 6064);
FORCEADD Q_RES..1
(-2150 5075);
FORCEPROP 1 LAST LOCATION R6267
J 0
(-2425 5075);
DISPLAY 0.808511 (-2425 5075);
FORCEPROP 0 LAST $SEC 1
J 0
(-2275 5175);
DISPLAY 0.680851 (-2275 5175);
PAINT MONO (-2275 5175);
DISPLAY INVISIBLE (-2275 5175);
FORCEPROP 0 LAST CDS_SEC 1
J 0
(-2275 5175);
DISPLAY 0.680851 (-2275 5175);
DISPLAY INVISIBLE (-2275 5175);
FORCEPROP 1 LASTPIN (-2250 5075) $PN 1
J 0
(-2238 5087);
DISPLAY 0.787234 (-2238 5087);
PAINT MONO (-2238 5087);
FORCEPROP 1 LASTPIN (-2050 5075) $PN 2
J 0
(-2088 5087);
DISPLAY 0.787234 (-2088 5087);
PAINT MONO (-2088 5087);
FORCEPROP 1 LAST TOLERANCE 5%
J 0
(-1975 5075);
DISPLAY 0.617021 (-1975 5075);
FORCEPROP 1 LAST PACK_TYPE 0402LF
J 0
(-1900 5075);
DISPLAY 0.617021 (-1900 5075);
FORCEPROP 1 LAST MATERIAL CHIP
J 0
(-1700 5075);
DISPLAY 0.617021 (-1700 5075);
FORCEPROP 2 LAST ROOM USB3_HUB2_TI
J 0
(-2325 5150);
DISPLAY 0.680851 (-2325 5150);
PAINT RED (-2325 5150);
FORCEPROP 1 LAST VALUE 0
J 2
(-2000 5075);
DISPLAY 0.617021 (-2000 5075);
FORCEPROP 2 LAST CDS_LIB pure_quanta
J 0
(-2150 5075);
DISPLAY INVISIBLE (-2150 5075);
FORCEPROP 1 LAST WATTAGE 1/16W
J 2
(-1950 5025);
DISPLAY 0.617021 (-1950 5025);
DISPLAY INVISIBLE (-1950 5025);
FORCEPROP 2 LAST BOM_COST VR_SYSTEM 
J 0
(-2200 5225);
DISPLAY 0.680851 (-2200 5225);
DISPLAY INVISIBLE (-2200 5225);
FORCEPROP 1 LAST PATH I122
J 0
(-2200 5225);
DISPLAY 0.978723 (-2200 5225);
PAINT WHITE (-2200 5225);
DISPLAY INVISIBLE (-2200 5225);
FORCEPROP 1 LAST PART_NUMBER CS00002JB13
J 0
(-2300 5125);
DISPLAY 0.617021 (-2300 5125);
DISPLAY INVISIBLE (-2300 5125);
FORCEADD Q_RES..2
(-525 3375);
FORCEPROP 1 LAST LOCATION R6278
J 0
(-480 3500);
DISPLAY 0.638298 (-480 3500);
FORCEPROP 0 LAST $SEC 1
J 0
(-475 3550);
DISPLAY 0.680851 (-475 3550);
PAINT MONO (-475 3550);
DISPLAY INVISIBLE (-475 3550);
FORCEPROP 0 LAST CDS_SEC 1
J 0
(-475 3550);
DISPLAY 0.680851 (-475 3550);
DISPLAY INVISIBLE (-475 3550);
FORCEPROP 1 LASTPIN (-525 3475) $PN 1
J 0
(-520 3437);
DISPLAY 0.787234 (-520 3437);
PAINT MONO (-520 3437);
FORCEPROP 1 LASTPIN (-525 3275) $PN 2
J 0
(-520 3285);
DISPLAY 0.787234 (-520 3285);
PAINT MONO (-520 3285);
FORCEPROP 1 LAST VALUE 10K
J 0
(-480 3450);
DISPLAY 0.510638 (-480 3450);
FORCEPROP 1 LAST MATERIAL EMPTY
J 0
(-485 3300);
DISPLAY 0.510638 (-485 3300);
FORCEPROP 1 LAST PACK_TYPE 0402LF
J 0
(-485 3200);
DISPLAY 0.510638 (-485 3200);
FORCEPROP 1 LAST WATTAGE 1/16W
J 0
(-485 3350);
DISPLAY 0.510638 (-485 3350);
FORCEPROP 1 LAST TOLERANCE 1%
J 0
(-480 3400);
DISPLAY 0.510638 (-480 3400);
FORCEPROP 2 LAST ROOM USB3_HUB2_MRP
J 0
(-475 3150);
DISPLAY 0.553191 (-475 3150);
PAINT RED (-475 3150);
FORCEPROP 2 LAST CDS_LIB pure_quanta
J 0
(-525 3375);
DISPLAY INVISIBLE (-525 3375);
FORCEPROP 1 LAST PATH I124
J 0
(-475 3550);
DISPLAY 0.978723 (-475 3550);
PAINT WHITE (-475 3550);
DISPLAY INVISIBLE (-475 3550);
FORCEPROP 1 LAST PART_NUMBER CS31002FB08
J 0
(-485 3250);
DISPLAY 0.510638 (-485 3250);
DISPLAY INVISIBLE (-485 3250);
FORCEADD Q_RES..1
(-1800 3650);
FORCEPROP 1 LAST LOCATION R6276
J 0
(-2075 3650);
DISPLAY 0.808511 (-2075 3650);
FORCEPROP 0 LAST $SEC 1
J 0
(-1350 3700);
DISPLAY 0.680851 (-1350 3700);
PAINT MONO (-1350 3700);
DISPLAY INVISIBLE (-1350 3700);
FORCEPROP 0 LAST CDS_SEC 1
J 0
(-1350 3700);
DISPLAY 0.680851 (-1350 3700);
DISPLAY INVISIBLE (-1350 3700);
FORCEPROP 1 LASTPIN (-1900 3650) $PN 1
J 0
(-1888 3662);
DISPLAY 0.787234 (-1888 3662);
PAINT MONO (-1888 3662);
FORCEPROP 1 LASTPIN (-1700 3650) $PN 2
J 0
(-1738 3662);
DISPLAY 0.787234 (-1738 3662);
PAINT MONO (-1738 3662);
FORCEPROP 2 LAST ROOM USB3_HUB2_MRP
J 0
(-2050 3600);
DISPLAY 0.680851 (-2050 3600);
PAINT RED (-2050 3600);
FORCEPROP 1 LAST MATERIAL CHIP
J 0
(-1350 3650);
DISPLAY 0.617021 (-1350 3650);
FORCEPROP 1 LAST TOLERANCE 5%
J 0
(-1625 3650);
DISPLAY 0.617021 (-1625 3650);
FORCEPROP 1 LAST VALUE 0
J 2
(-1650 3650);
DISPLAY 0.617021 (-1650 3650);
FORCEPROP 1 LAST PACK_TYPE 0402LF
J 0
(-1550 3650);
DISPLAY 0.617021 (-1550 3650);
FORCEPROP 2 LAST BOM_COST VR_SYSTEM 
J 0
(-1850 3800);
DISPLAY 0.680851 (-1850 3800);
DISPLAY INVISIBLE (-1850 3800);
FORCEPROP 1 LAST WATTAGE 1/16W
J 2
(-1600 3600);
DISPLAY 0.617021 (-1600 3600);
DISPLAY INVISIBLE (-1600 3600);
FORCEPROP 2 LAST CDS_LIB pure_quanta
J 0
(-1800 3650);
DISPLAY INVISIBLE (-1800 3650);
FORCEPROP 1 LAST PATH I125
J 0
(-1850 3800);
DISPLAY 0.978723 (-1850 3800);
PAINT WHITE (-1850 3800);
DISPLAY INVISIBLE (-1850 3800);
FORCEPROP 1 LAST PART_NUMBER CS00002JB13
J 0
(-1950 3700);
DISPLAY 0.617021 (-1950 3700);
DISPLAY INVISIBLE (-1950 3700);
FORCEADD UNIVERSAL_POWER..1
(-525 4075);
FORCEPROP 3 LASTPIN (-525 4025) SIG_NAME P3V3_AUX\g
J 0
(-515 4035);
DISPLAY 0.659574 (-515 4035);
PAINT MONO (-515 4035);
DISPLAY INVISIBLE (-515 4035);
FORCEPROP 1 LAST HDL_POWER P3V3_AUX
J 1
(-525 4125);
DISPLAY 0.489362 (-525 4125);
PAINT GREEN (-525 4125);
FORCEPROP 2 LAST CDS_LIB pure_quanta_power
J 0
(-525 4075);
DISPLAY INVISIBLE (-525 4075);
FORCEPROP 2 LAST BOM_COST VR_SYSTEM
J 0
(-525 4175);
DISPLAY 0.617021 (-525 4175);
PAINT PURPLE (-525 4175);
DISPLAY INVISIBLE (-525 4175);
FORCEPROP 1 LAST PATH I128
J 0
(-475 4100);
DISPLAY 0.872340 (-475 4100);
PAINT AQUA (-475 4100);
DISPLAY INVISIBLE (-475 4100);
FORCEADD GND..1
(-525 3075);
FORCEPROP 3 LASTPIN (-525 3125) SIG_NAME GND\g
J 0
(-515 3135);
DISPLAY 0.659574 (-515 3135);
PAINT MONO (-515 3135);
DISPLAY INVISIBLE (-515 3135);
FORCEPROP 1 LAST SIZE 1B
J 0
(-450 3025);
DISPLAY 1.170213 (-450 3025);
PAINT AQUA (-450 3025);
DISPLAY INVISIBLE (-450 3025);
FORCEPROP 2 LAST CDS_LIB pure_quanta_power
J 0
(-525 3075);
DISPLAY INVISIBLE (-525 3075);
FORCEPROP 1 LAST HDL_POWER GND
J 0
(-525 3225);
DISPLAY 1.170213 (-525 3225);
PAINT GREEN (-525 3225);
DISPLAY INVISIBLE (-525 3225);
FORCEPROP 1 LAST PATH I129
J 0
(-450 3075);
DISPLAY 0.872340 (-450 3075);
PAINT AQUA (-450 3075);
DISPLAY INVISIBLE (-450 3075);
FORCEADD Q_RES..2
(-525 3800);
FORCEPROP 1 LAST LOCATION R6277
J 0
(-480 3925);
DISPLAY 0.638298 (-480 3925);
FORCEPROP 0 LAST $SEC 1
J 0
(-475 3975);
DISPLAY 0.680851 (-475 3975);
PAINT MONO (-475 3975);
DISPLAY INVISIBLE (-475 3975);
FORCEPROP 0 LAST CDS_SEC 1
J 0
(-475 3975);
DISPLAY 0.680851 (-475 3975);
DISPLAY INVISIBLE (-475 3975);
FORCEPROP 1 LASTPIN (-525 3900) $PN 1
J 0
(-520 3862);
DISPLAY 0.787234 (-520 3862);
PAINT MONO (-520 3862);
FORCEPROP 1 LASTPIN (-525 3700) $PN 2
J 0
(-520 3710);
DISPLAY 0.787234 (-520 3710);
PAINT MONO (-520 3710);
FORCEPROP 1 LAST VALUE 10K
J 0
(-480 3875);
DISPLAY 0.510638 (-480 3875);
FORCEPROP 1 LAST PACK_TYPE 0402LF
J 0
(-475 3625);
DISPLAY 0.510638 (-475 3625);
FORCEPROP 1 LAST TOLERANCE 1%
J 0
(-480 3825);
DISPLAY 0.510638 (-480 3825);
FORCEPROP 1 LAST WATTAGE 1/16W
J 0
(-485 3775);
DISPLAY 0.510638 (-485 3775);
FORCEPROP 2 LAST ROOM USB3_HUB2_MRP
J 0
(-500 3975);
DISPLAY 0.553191 (-500 3975);
PAINT RED (-500 3975);
FORCEPROP 1 LAST MATERIAL EMPTY
J 0
(-485 3725);
DISPLAY 0.510638 (-485 3725);
FORCEPROP 2 LAST CDS_LIB pure_quanta
J 0
(-525 3800);
DISPLAY INVISIBLE (-525 3800);
FORCEPROP 1 LAST PATH I130
J 0
(-475 3975);
DISPLAY 0.978723 (-475 3975);
PAINT WHITE (-475 3975);
DISPLAY INVISIBLE (-475 3975);
FORCEPROP 1 LAST PART_NUMBER CS31002FB08
J 0
(-485 3675);
DISPLAY 0.510638 (-485 3675);
DISPLAY INVISIBLE (-485 3675);
FORCEADD Q_RES..1
(-1800 3725);
FORCEPROP 1 LAST LOCATION R6275
J 0
(-2075 3725);
DISPLAY 0.808511 (-2075 3725);
FORCEPROP 0 LAST $SEC 1
J 0
(-1925 3825);
DISPLAY 0.680851 (-1925 3825);
PAINT MONO (-1925 3825);
DISPLAY INVISIBLE (-1925 3825);
FORCEPROP 0 LAST CDS_SEC 1
J 0
(-1925 3825);
DISPLAY 0.680851 (-1925 3825);
DISPLAY INVISIBLE (-1925 3825);
FORCEPROP 1 LASTPIN (-1900 3725) $PN 1
J 0
(-1888 3737);
DISPLAY 0.787234 (-1888 3737);
PAINT MONO (-1888 3737);
FORCEPROP 1 LASTPIN (-1700 3725) $PN 2
J 0
(-1738 3737);
DISPLAY 0.787234 (-1738 3737);
PAINT MONO (-1738 3737);
FORCEPROP 1 LAST MATERIAL CHIP
J 0
(-1350 3725);
DISPLAY 0.617021 (-1350 3725);
FORCEPROP 2 LAST ROOM USB3_HUB2_TI
J 0
(-1975 3800);
DISPLAY 0.680851 (-1975 3800);
PAINT RED (-1975 3800);
FORCEPROP 1 LAST VALUE 0
J 2
(-1650 3725);
DISPLAY 0.617021 (-1650 3725);
FORCEPROP 1 LAST PACK_TYPE 0402LF
J 0
(-1550 3725);
DISPLAY 0.617021 (-1550 3725);
FORCEPROP 1 LAST TOLERANCE 5%
J 0
(-1625 3725);
DISPLAY 0.617021 (-1625 3725);
FORCEPROP 2 LAST BOM_COST VR_SYSTEM 
J 0
(-1850 3875);
DISPLAY 0.680851 (-1850 3875);
DISPLAY INVISIBLE (-1850 3875);
FORCEPROP 1 LAST WATTAGE 1/16W
J 2
(-1600 3675);
DISPLAY 0.617021 (-1600 3675);
DISPLAY INVISIBLE (-1600 3675);
FORCEPROP 2 LAST CDS_LIB pure_quanta
J 0
(-1800 3725);
DISPLAY INVISIBLE (-1800 3725);
FORCEPROP 1 LAST PATH I131
J 0
(-1850 3875);
DISPLAY 0.978723 (-1850 3875);
PAINT WHITE (-1850 3875);
DISPLAY INVISIBLE (-1850 3875);
FORCEPROP 1 LAST PART_NUMBER CS00002JB13
J 0
(-1950 3775);
DISPLAY 0.617021 (-1950 3775);
DISPLAY INVISIBLE (-1950 3775);
FORCEADD UNIVERSAL_POWER..1
(-1200 4050);
FORCEPROP 3 LASTPIN (-1200 4000) SIG_NAME P3V3_AUX_CPU0_USB2_AVDD33\g
J 0
(-1190 4010);
DISPLAY 0.659574 (-1190 4010);
PAINT MONO (-1190 4010);
DISPLAY INVISIBLE (-1190 4010);
FORCEPROP 1 LAST HDL_POWER P3V3_AUX_CPU0_USB2_AVDD33
J 1
(-1200 4100);
DISPLAY 0.489362 (-1200 4100);
PAINT GREEN (-1200 4100);
FORCEPROP 2 LAST BOM_COST VR_SYSTEM
J 0
(-1200 4150);
DISPLAY 0.617021 (-1200 4150);
PAINT PURPLE (-1200 4150);
DISPLAY INVISIBLE (-1200 4150);
FORCEPROP 2 LAST CDS_LIB pure_quanta_power
J 0
(-1200 4050);
DISPLAY INVISIBLE (-1200 4050);
FORCEPROP 1 LAST PATH I132
J 0
(-1150 4075);
DISPLAY 0.872340 (-1150 4075);
PAINT AQUA (-1150 4075);
DISPLAY INVISIBLE (-1150 4075);
FORCEADD UNIVERSAL_POWER..1
(-1500 5800);
FORCEPROP 3 LASTPIN (-1500 5750) SIG_NAME P1V2_CPU0_USB2_DVDD12\g
J 0
(-1490 5760);
DISPLAY 0.659574 (-1490 5760);
PAINT MONO (-1490 5760);
DISPLAY INVISIBLE (-1490 5760);
FORCEPROP 1 LAST HDL_POWER P1V2_CPU0_USB2_DVDD12
J 1
(-1500 5850);
DISPLAY 0.617021 (-1500 5850);
PAINT GREEN (-1500 5850);
FORCEPROP 2 LAST BOM_COST VR_SYSTEM
J 0
(-1500 5900);
DISPLAY 0.617021 (-1500 5900);
PAINT PURPLE (-1500 5900);
DISPLAY INVISIBLE (-1500 5900);
FORCEPROP 2 LAST CDS_LIB pure_quanta_power
J 0
(-1500 5800);
DISPLAY INVISIBLE (-1500 5800);
FORCEPROP 1 LAST PATH I133
J 0
(-1450 5825);
DISPLAY 0.872340 (-1450 5825);
PAINT AQUA (-1450 5825);
DISPLAY INVISIBLE (-1450 5825);
FORCEADD Q_RES..1
(-2125 5525);
FORCEPROP 1 LAST LOCATION R6262
J 0
(-2400 5525);
DISPLAY 0.808511 (-2400 5525);
FORCEPROP 0 LAST $SEC 1
J 0
(-2250 5625);
DISPLAY 0.680851 (-2250 5625);
PAINT MONO (-2250 5625);
DISPLAY INVISIBLE (-2250 5625);
FORCEPROP 0 LAST CDS_SEC 1
J 0
(-2250 5625);
DISPLAY 0.680851 (-2250 5625);
DISPLAY INVISIBLE (-2250 5625);
FORCEPROP 1 LASTPIN (-2225 5525) $PN 1
J 0
(-2213 5537);
DISPLAY 0.787234 (-2213 5537);
PAINT MONO (-2213 5537);
FORCEPROP 1 LASTPIN (-2025 5525) $PN 2
J 0
(-2063 5537);
DISPLAY 0.787234 (-2063 5537);
PAINT MONO (-2063 5537);
FORCEPROP 1 LAST MATERIAL CHIP
J 0
(-1675 5525);
DISPLAY 0.617021 (-1675 5525);
FORCEPROP 1 LAST PACK_TYPE 0402LF
J 0
(-1875 5525);
DISPLAY 0.617021 (-1875 5525);
FORCEPROP 2 LAST ROOM USB3_HUB2_TI
J 0
(-2325 5600);
DISPLAY 0.680851 (-2325 5600);
PAINT RED (-2325 5600);
FORCEPROP 1 LAST TOLERANCE 5%
J 0
(-1950 5525);
DISPLAY 0.617021 (-1950 5525);
FORCEPROP 1 LAST VALUE 0
J 2
(-1975 5525);
DISPLAY 0.617021 (-1975 5525);
FORCEPROP 2 LAST CDS_LIB pure_quanta
J 0
(-2125 5525);
DISPLAY INVISIBLE (-2125 5525);
FORCEPROP 2 LAST BOM_COST VR_SYSTEM 
J 0
(-2175 5675);
DISPLAY 0.680851 (-2175 5675);
DISPLAY INVISIBLE (-2175 5675);
FORCEPROP 1 LAST WATTAGE 1/16W
J 2
(-1925 5475);
DISPLAY 0.617021 (-1925 5475);
DISPLAY INVISIBLE (-1925 5475);
FORCEPROP 1 LAST PATH I134
J 0
(-2175 5675);
DISPLAY 0.978723 (-2175 5675);
PAINT WHITE (-2175 5675);
DISPLAY INVISIBLE (-2175 5675);
FORCEPROP 1 LAST PART_NUMBER CS00002JB13
J 0
(-2275 5575);
DISPLAY 0.617021 (-2275 5575);
DISPLAY INVISIBLE (-2275 5575);
FORCEADD Q_RES..1
(-2125 4925);
FORCEPROP 1 LAST LOCATION R6269
J 0
(-2400 4925);
DISPLAY 0.808511 (-2400 4925);
FORCEPROP 0 LAST $SEC 1
J 0
(-2250 5025);
DISPLAY 0.680851 (-2250 5025);
PAINT MONO (-2250 5025);
DISPLAY INVISIBLE (-2250 5025);
FORCEPROP 0 LAST CDS_SEC 1
J 0
(-2250 5025);
DISPLAY 0.680851 (-2250 5025);
DISPLAY INVISIBLE (-2250 5025);
FORCEPROP 1 LASTPIN (-2225 4925) $PN 1
J 0
(-2213 4937);
DISPLAY 0.787234 (-2213 4937);
PAINT MONO (-2213 4937);
FORCEPROP 1 LASTPIN (-2025 4925) $PN 2
J 0
(-2063 4937);
DISPLAY 0.787234 (-2063 4937);
PAINT MONO (-2063 4937);
FORCEPROP 1 LAST PACK_TYPE 0402LF
J 0
(-1875 4925);
DISPLAY 0.617021 (-1875 4925);
FORCEPROP 1 LAST MATERIAL CHIP
J 0
(-1675 4925);
DISPLAY 0.617021 (-1675 4925);
FORCEPROP 1 LAST VALUE 0
J 2
(-1975 4925);
DISPLAY 0.617021 (-1975 4925);
FORCEPROP 1 LAST TOLERANCE 5%
J 0
(-1950 4925);
DISPLAY 0.617021 (-1950 4925);
FORCEPROP 2 LAST ROOM USB3_HUB2_TI
J 0
(-2325 5000);
DISPLAY 0.680851 (-2325 5000);
PAINT RED (-2325 5000);
FORCEPROP 1 LAST WATTAGE 1/16W
J 2
(-1925 4875);
DISPLAY 0.617021 (-1925 4875);
DISPLAY INVISIBLE (-1925 4875);
FORCEPROP 2 LAST BOM_COST VR_SYSTEM 
J 0
(-2175 5075);
DISPLAY 0.680851 (-2175 5075);
DISPLAY INVISIBLE (-2175 5075);
FORCEPROP 2 LAST CDS_LIB pure_quanta
J 0
(-2125 4925);
DISPLAY INVISIBLE (-2125 4925);
FORCEPROP 1 LAST PATH I136
J 0
(-2175 5075);
DISPLAY 0.978723 (-2175 5075);
PAINT WHITE (-2175 5075);
DISPLAY INVISIBLE (-2175 5075);
FORCEPROP 1 LAST PART_NUMBER CS00002JB13
J 0
(-2275 4975);
DISPLAY 0.617021 (-2275 4975);
DISPLAY INVISIBLE (-2275 4975);
FORCEADD UNIVERSAL_POWER..1
(-8850 6275);
FORCEPROP 3 LASTPIN (-8850 6225) SIG_NAME P3V3_AUX\g
J 0
(-8840 6235);
DISPLAY 0.659574 (-8840 6235);
PAINT MONO (-8840 6235);
DISPLAY INVISIBLE (-8840 6235);
FORCEPROP 1 LAST HDL_POWER P3V3_AUX
J 1
(-8850 6325);
DISPLAY 0.489362 (-8850 6325);
PAINT GREEN (-8850 6325);
FORCEPROP 2 LAST CDS_LIB pure_quanta_power
J 0
(-8850 6275);
DISPLAY INVISIBLE (-8850 6275);
FORCEPROP 2 LAST BOM_COST VR_SYSTEM
J 0
(-8850 6375);
DISPLAY 0.617021 (-8850 6375);
PAINT PURPLE (-8850 6375);
DISPLAY INVISIBLE (-8850 6375);
FORCEPROP 1 LAST PATH I137
J 0
(-8800 6300);
DISPLAY 0.872340 (-8800 6300);
PAINT AQUA (-8800 6300);
DISPLAY INVISIBLE (-8800 6300);
FORCEADD Q_RES..2
(-8850 5975);
FORCEPROP 1 LAST LOCATION R6282
J 0
(-8805 6100);
DISPLAY 0.638298 (-8805 6100);
FORCEPROP 0 LAST $SEC 1
J 0
(-8800 6150);
DISPLAY 0.680851 (-8800 6150);
PAINT MONO (-8800 6150);
DISPLAY INVISIBLE (-8800 6150);
FORCEPROP 0 LAST CDS_SEC 1
J 0
(-8800 6150);
DISPLAY 0.680851 (-8800 6150);
DISPLAY INVISIBLE (-8800 6150);
FORCEPROP 1 LASTPIN (-8850 6075) $PN 1
J 0
(-8845 6037);
DISPLAY 0.787234 (-8845 6037);
PAINT MONO (-8845 6037);
FORCEPROP 1 LASTPIN (-8850 5875) $PN 2
J 0
(-8845 5885);
DISPLAY 0.787234 (-8845 5885);
PAINT MONO (-8845 5885);
FORCEPROP 1 LAST MATERIAL EMPTY
J 0
(-8810 5900);
DISPLAY 0.638298 (-8810 5900);
PAINT RED (-8810 5900);
FORCEPROP 1 LAST WATTAGE 1/16W
J 0
(-8810 5950);
DISPLAY 0.638298 (-8810 5950);
FORCEPROP 2 LAST ROOM USB3_HUB2_TI
J 0
(-8775 5750);
DISPLAY 0.680851 (-8775 5750);
PAINT RED (-8775 5750);
FORCEPROP 1 LAST TOLERANCE 1%
J 0
(-8805 6000);
DISPLAY 0.638298 (-8805 6000);
FORCEPROP 1 LAST PACK_TYPE 0402LF
J 0
(-8810 5800);
DISPLAY 0.638298 (-8810 5800);
FORCEPROP 1 LAST VALUE 1K
J 0
(-8805 6050);
DISPLAY 0.638298 (-8805 6050);
FORCEPROP 2 LAST CDS_LIB pure_quanta
J 0
(-8850 5975);
DISPLAY INVISIBLE (-8850 5975);
FORCEPROP 1 LAST PATH I138
J 0
(-8800 6150);
DISPLAY 0.978723 (-8800 6150);
PAINT WHITE (-8800 6150);
DISPLAY INVISIBLE (-8800 6150);
FORCEPROP 1 LAST PART_NUMBER CS21002FB06
J 0
(-8810 5850);
DISPLAY 0.638298 (-8810 5850);
DISPLAY INVISIBLE (-8810 5850);
FORCEADD Q_RES..2
(-8850 5500);
FORCEPROP 1 LAST LOCATION R6281
J 0
(-8805 5625);
DISPLAY 0.638298 (-8805 5625);
FORCEPROP 0 LAST $SEC 1
J 0
(-8800 5675);
DISPLAY 0.680851 (-8800 5675);
PAINT MONO (-8800 5675);
DISPLAY INVISIBLE (-8800 5675);
FORCEPROP 0 LAST CDS_SEC 1
J 0
(-8800 5675);
DISPLAY 0.680851 (-8800 5675);
DISPLAY INVISIBLE (-8800 5675);
FORCEPROP 1 LASTPIN (-8850 5600) $PN 1
J 0
(-8845 5562);
DISPLAY 0.787234 (-8845 5562);
PAINT MONO (-8845 5562);
FORCEPROP 1 LASTPIN (-8850 5400) $PN 2
J 0
(-8845 5410);
DISPLAY 0.787234 (-8845 5410);
PAINT MONO (-8845 5410);
FORCEPROP 1 LAST MATERIAL EMPTY
J 0
(-8810 5425);
DISPLAY 0.638298 (-8810 5425);
PAINT RED (-8810 5425);
FORCEPROP 1 LAST WATTAGE 1/16W
J 0
(-8810 5475);
DISPLAY 0.638298 (-8810 5475);
FORCEPROP 1 LAST TOLERANCE 1%
J 0
(-8805 5525);
DISPLAY 0.638298 (-8805 5525);
FORCEPROP 1 LAST VALUE 1K
J 0
(-8805 5575);
DISPLAY 0.638298 (-8805 5575);
FORCEPROP 1 LAST PACK_TYPE 0402LF
J 0
(-8810 5325);
DISPLAY 0.638298 (-8810 5325);
FORCEPROP 2 LAST ROOM USB3_HUB2_TI
J 0
(-8800 5275);
DISPLAY 0.553191 (-8800 5275);
PAINT RED (-8800 5275);
FORCEPROP 2 LAST CDS_LIB pure_quanta
J 0
(-8850 5500);
DISPLAY INVISIBLE (-8850 5500);
FORCEPROP 1 LAST PATH I139
J 0
(-8800 5675);
DISPLAY 0.978723 (-8800 5675);
PAINT WHITE (-8800 5675);
DISPLAY INVISIBLE (-8800 5675);
FORCEPROP 1 LAST PART_NUMBER CS21002FB06
J 0
(-8810 5375);
DISPLAY 0.638298 (-8810 5375);
DISPLAY INVISIBLE (-8810 5375);
FORCEADD GND..1
(-8850 5250);
FORCEPROP 3 LASTPIN (-8850 5300) SIG_NAME GND\g
J 0
(-8840 5310);
DISPLAY 0.659574 (-8840 5310);
PAINT MONO (-8840 5310);
DISPLAY INVISIBLE (-8840 5310);
FORCEPROP 2 LAST CDS_LIB pure_quanta_power
J 0
(-8850 5250);
DISPLAY INVISIBLE (-8850 5250);
FORCEPROP 1 LAST SIZE 1B
J 0
(-8775 5200);
DISPLAY 1.170213 (-8775 5200);
PAINT AQUA (-8775 5200);
DISPLAY INVISIBLE (-8775 5200);
FORCEPROP 1 LAST HDL_POWER GND
J 0
(-8850 5400);
DISPLAY 1.170213 (-8850 5400);
PAINT GREEN (-8850 5400);
DISPLAY INVISIBLE (-8850 5400);
FORCEPROP 1 LAST PATH I140
J 0
(-8775 5250);
DISPLAY 0.872340 (-8775 5250);
PAINT AQUA (-8775 5250);
DISPLAY INVISIBLE (-8775 5250);
FORCEADD Q_RES..1
(-2150 3875);
FORCEPROP 1 LAST LOCATION R6274
J 0
(-2425 3875);
DISPLAY 0.808511 (-2425 3875);
FORCEPROP 0 LAST $SEC 1
J 0
(-2275 3975);
DISPLAY 0.680851 (-2275 3975);
PAINT MONO (-2275 3975);
DISPLAY INVISIBLE (-2275 3975);
FORCEPROP 0 LAST CDS_SEC 1
J 0
(-2275 3975);
DISPLAY 0.680851 (-2275 3975);
DISPLAY INVISIBLE (-2275 3975);
FORCEPROP 1 LASTPIN (-2250 3875) $PN 1
J 0
(-2238 3887);
DISPLAY 0.787234 (-2238 3887);
PAINT MONO (-2238 3887);
FORCEPROP 1 LASTPIN (-2050 3875) $PN 2
J 0
(-2088 3887);
DISPLAY 0.787234 (-2088 3887);
PAINT MONO (-2088 3887);
FORCEPROP 2 LAST ROOM USB3_HUB2_TI
J 0
(-2325 3950);
DISPLAY 0.680851 (-2325 3950);
PAINT RED (-2325 3950);
FORCEPROP 1 LAST MATERIAL CHIP
J 0
(-1700 3875);
DISPLAY 0.617021 (-1700 3875);
FORCEPROP 1 LAST PACK_TYPE 0402LF
J 0
(-1900 3875);
DISPLAY 0.617021 (-1900 3875);
FORCEPROP 1 LAST TOLERANCE 5%
J 0
(-1975 3875);
DISPLAY 0.617021 (-1975 3875);
FORCEPROP 1 LAST VALUE 0
J 2
(-2000 3875);
DISPLAY 0.617021 (-2000 3875);
FORCEPROP 2 LAST CDS_LIB pure_quanta
J 0
(-2150 3875);
DISPLAY INVISIBLE (-2150 3875);
FORCEPROP 2 LAST BOM_COST VR_SYSTEM 
J 0
(-2200 4025);
DISPLAY 0.680851 (-2200 4025);
DISPLAY INVISIBLE (-2200 4025);
FORCEPROP 1 LAST WATTAGE 1/16W
J 2
(-1950 3825);
DISPLAY 0.617021 (-1950 3825);
DISPLAY INVISIBLE (-1950 3825);
FORCEPROP 1 LAST PATH I142
J 0
(-2200 4025);
DISPLAY 0.978723 (-2200 4025);
PAINT WHITE (-2200 4025);
DISPLAY INVISIBLE (-2200 4025);
FORCEPROP 1 LAST PART_NUMBER CS00002JB13
J 0
(-2300 3925);
DISPLAY 0.617021 (-2300 3925);
DISPLAY INVISIBLE (-2300 3925);
FORCEADD Q_RES..1
(-2125 5225);
FORCEPROP 1 LAST LOCATION R6265
J 0
(-2400 5225);
DISPLAY 0.808511 (-2400 5225);
FORCEPROP 0 LAST $SEC 1
J 0
(-2250 5325);
DISPLAY 0.680851 (-2250 5325);
PAINT MONO (-2250 5325);
DISPLAY INVISIBLE (-2250 5325);
FORCEPROP 0 LAST CDS_SEC 1
J 0
(-2250 5325);
DISPLAY 0.680851 (-2250 5325);
DISPLAY INVISIBLE (-2250 5325);
FORCEPROP 1 LASTPIN (-2225 5225) $PN 1
J 0
(-2213 5237);
DISPLAY 0.787234 (-2213 5237);
PAINT MONO (-2213 5237);
FORCEPROP 1 LASTPIN (-2025 5225) $PN 2
J 0
(-2063 5237);
DISPLAY 0.787234 (-2063 5237);
PAINT MONO (-2063 5237);
FORCEPROP 1 LAST PACK_TYPE 0402LF
J 0
(-1875 5225);
DISPLAY 0.617021 (-1875 5225);
FORCEPROP 1 LAST MATERIAL CHIP
J 0
(-1675 5225);
DISPLAY 0.617021 (-1675 5225);
FORCEPROP 1 LAST VALUE 0
J 2
(-1975 5225);
DISPLAY 0.617021 (-1975 5225);
FORCEPROP 2 LAST ROOM USB3_HUB2_TI
J 0
(-2325 5300);
DISPLAY 0.680851 (-2325 5300);
PAINT RED (-2325 5300);
FORCEPROP 1 LAST TOLERANCE 5%
J 0
(-1950 5225);
DISPLAY 0.617021 (-1950 5225);
FORCEPROP 2 LAST CDS_LIB pure_quanta
J 0
(-2125 5225);
DISPLAY INVISIBLE (-2125 5225);
FORCEPROP 2 LAST BOM_COST VR_SYSTEM 
J 0
(-2175 5375);
DISPLAY 0.680851 (-2175 5375);
DISPLAY INVISIBLE (-2175 5375);
FORCEPROP 1 LAST WATTAGE 1/16W
J 2
(-1925 5175);
DISPLAY 0.617021 (-1925 5175);
DISPLAY INVISIBLE (-1925 5175);
FORCEPROP 1 LAST PATH I145
J 0
(-2175 5375);
DISPLAY 0.978723 (-2175 5375);
PAINT WHITE (-2175 5375);
DISPLAY INVISIBLE (-2175 5375);
FORCEPROP 1 LAST PART_NUMBER CS00002JB13
J 0
(-2275 5275);
DISPLAY 0.617021 (-2275 5275);
DISPLAY INVISIBLE (-2275 5275);
FORCEADD Q_RES..1
(-6800 5275);
FORCEPROP 1 LAST LOCATION R6280
J 0
(-7025 5225);
DISPLAY 0.808511 (-7025 5225);
FORCEPROP 0 LAST $SEC 1
J 0
(-6925 5375);
DISPLAY 0.680851 (-6925 5375);
PAINT MONO (-6925 5375);
DISPLAY INVISIBLE (-6925 5375);
FORCEPROP 0 LAST CDS_SEC 1
J 0
(-6925 5375);
DISPLAY 0.680851 (-6925 5375);
DISPLAY INVISIBLE (-6925 5375);
FORCEPROP 1 LASTPIN (-6900 5275) $PN 1
J 0
(-6888 5287);
DISPLAY 0.787234 (-6888 5287);
PAINT MONO (-6888 5287);
FORCEPROP 1 LASTPIN (-6700 5275) $PN 2
J 0
(-6738 5287);
DISPLAY 0.787234 (-6738 5287);
PAINT MONO (-6738 5287);
FORCEPROP 2 LAST ROOM USB3_HUB2_TI
J 0
(-6925 5325);
DISPLAY 0.680851 (-6925 5325);
PAINT RED (-6925 5325);
FORCEPROP 1 LAST PACK_TYPE 0402LF
J 0
(-6550 5275);
DISPLAY 0.617021 (-6550 5275);
FORCEPROP 1 LAST MATERIAL CHIP
J 0
(-6725 5225);
DISPLAY 0.617021 (-6725 5225);
FORCEPROP 1 LAST TOLERANCE 5%
J 0
(-6625 5275);
DISPLAY 0.617021 (-6625 5275);
FORCEPROP 1 LAST VALUE 0
J 2
(-6650 5275);
DISPLAY 0.617021 (-6650 5275);
FORCEPROP 2 LAST BOM_COST VR_SYSTEM 
J 0
(-6850 5425);
DISPLAY 0.680851 (-6850 5425);
DISPLAY INVISIBLE (-6850 5425);
FORCEPROP 1 LAST WATTAGE 1/16W
J 2
(-6600 5225);
DISPLAY 0.617021 (-6600 5225);
DISPLAY INVISIBLE (-6600 5225);
FORCEPROP 2 LAST CDS_LIB pure_quanta
J 0
(-6800 5275);
DISPLAY INVISIBLE (-6800 5275);
FORCEPROP 1 LAST PATH I146
J 0
(-6850 5425);
DISPLAY 0.978723 (-6850 5425);
PAINT WHITE (-6850 5425);
DISPLAY INVISIBLE (-6850 5425);
FORCEPROP 1 LAST PART_NUMBER CS00002JB13
J 0
(-6950 5325);
DISPLAY 0.617021 (-6950 5325);
DISPLAY INVISIBLE (-6950 5325);
FORCEADD OFFPAGE..3
R 2
(-7825 5275);
FORCEPROP 2 LAST $XR2 178 
J 0
(-8375 5275);
DISPLAY 0.638298 (-8375 5275);
PAINT MONO (-8375 5275);
FORCEPROP 2 LAST $XR1 176 
J 0
(-8255 5275);
DISPLAY 0.638298 (-8255 5275);
PAINT MONO (-8255 5275);
FORCEPROP 2 LAST $XR0 251 
J 0
(-8135 5275);
DISPLAY 0.638298 (-8135 5275);
PAINT MONO (-8135 5275);
FORCEPROP 2 LAST CDS_LIB standard
J 0
(-7825 5275);
DISPLAY INVISIBLE (-7825 5275);
FORCEPROP 1 LAST OFFPAGE TRUE
J 2
(-8150 5150);
DISPLAY 0.872340 (-8150 5150);
PAINT GREEN (-8150 5150);
DISPLAY INVISIBLE (-8150 5150);
FORCEPROP 1 LAST COMMENT_BODY TRUE
J 2
(-7775 5175);
DISPLAY 0.872340 (-7775 5175);
PAINT GREEN (-7775 5175);
DISPLAY INVISIBLE (-7775 5175);
FORCEPROP 2 LAST PATH I147
J 0
(-8100 5325);
DISPLAY 0.680851 (-8100 5325);
DISPLAY INVISIBLE (-8100 5325);
FORCEADD Q_RES..1
(-6775 5475);
FORCEPROP 1 LAST LOCATION R6279
J 0
(-7000 5425);
DISPLAY 0.808511 (-7000 5425);
FORCEPROP 0 LAST $SEC 1
J 0
(-6900 5575);
DISPLAY 0.680851 (-6900 5575);
PAINT MONO (-6900 5575);
DISPLAY INVISIBLE (-6900 5575);
FORCEPROP 0 LAST CDS_SEC 1
J 0
(-6900 5575);
DISPLAY 0.680851 (-6900 5575);
DISPLAY INVISIBLE (-6900 5575);
FORCEPROP 1 LASTPIN (-6875 5475) $PN 1
J 0
(-6863 5487);
DISPLAY 0.787234 (-6863 5487);
PAINT MONO (-6863 5487);
FORCEPROP 1 LASTPIN (-6675 5475) $PN 2
J 0
(-6713 5487);
DISPLAY 0.787234 (-6713 5487);
PAINT MONO (-6713 5487);
FORCEPROP 1 LAST MATERIAL CHIP
J 0
(-6675 5425);
DISPLAY 0.617021 (-6675 5425);
FORCEPROP 1 LAST PACK_TYPE 0402LF
J 0
(-6525 5475);
DISPLAY 0.617021 (-6525 5475);
FORCEPROP 1 LAST TOLERANCE 5%
J 0
(-6600 5475);
DISPLAY 0.617021 (-6600 5475);
FORCEPROP 1 LAST VALUE 0
J 2
(-6625 5475);
DISPLAY 0.617021 (-6625 5475);
FORCEPROP 2 LAST ROOM USB3_HUB2_TI
J 0
(-6925 5550);
DISPLAY 0.680851 (-6925 5550);
PAINT RED (-6925 5550);
FORCEPROP 2 LAST CDS_LIB pure_quanta
J 0
(-6775 5475);
DISPLAY INVISIBLE (-6775 5475);
FORCEPROP 1 LAST WATTAGE 1/16W
J 2
(-6575 5425);
DISPLAY 0.617021 (-6575 5425);
DISPLAY INVISIBLE (-6575 5425);
FORCEPROP 2 LAST BOM_COST VR_SYSTEM 
J 0
(-6825 5625);
DISPLAY 0.680851 (-6825 5625);
DISPLAY INVISIBLE (-6825 5625);
FORCEPROP 1 LAST PATH I148
J 0
(-6825 5625);
DISPLAY 0.978723 (-6825 5625);
PAINT WHITE (-6825 5625);
DISPLAY INVISIBLE (-6825 5625);
FORCEPROP 1 LAST PART_NUMBER CS00002JB13
J 0
(-6925 5525);
DISPLAY 0.617021 (-6925 5525);
DISPLAY INVISIBLE (-6925 5525);
FORCEADD OFFPAGE..3
R 2
(-7800 5475);
FORCEPROP 2 LAST $XR2 251 
J 0
(-8320 5475);
DISPLAY 0.638298 (-8320 5475);
PAINT MONO (-8320 5475);
FORCEPROP 2 LAST $XR1 178 
J 0
(-8200 5475);
DISPLAY 0.638298 (-8200 5475);
PAINT MONO (-8200 5475);
FORCEPROP 2 LAST $XR0 176 
J 0
(-8080 5475);
DISPLAY 0.638298 (-8080 5475);
PAINT MONO (-8080 5475);
FORCEPROP 2 LAST CDS_LIB standard
J 2
(-7800 5475);
DISPLAY INVISIBLE (-7800 5475);
FORCEPROP 1 LAST OFFPAGE TRUE
J 2
(-8125 5350);
DISPLAY 0.872340 (-8125 5350);
PAINT GREEN (-8125 5350);
DISPLAY INVISIBLE (-8125 5350);
FORCEPROP 1 LAST COMMENT_BODY TRUE
J 2
(-7750 5375);
DISPLAY 0.872340 (-7750 5375);
PAINT GREEN (-7750 5375);
DISPLAY INVISIBLE (-7750 5375);
FORCEPROP 2 LAST PATH I149
J 0
(-8100 5525);
DISPLAY 0.680851 (-8100 5525);
DISPLAY INVISIBLE (-8100 5525);
FORCEADD Q_RES..1
(-7450 4750);
FORCEPROP 1 LAST LOCATION R6305
J 0
(-7750 4750);
DISPLAY 0.808511 (-7750 4750);
FORCEPROP 0 LAST $SEC 1
J 0
(-7000 4800);
DISPLAY 0.680851 (-7000 4800);
PAINT MONO (-7000 4800);
DISPLAY INVISIBLE (-7000 4800);
FORCEPROP 0 LAST CDS_SEC 1
J 0
(-7000 4800);
DISPLAY 0.680851 (-7000 4800);
DISPLAY INVISIBLE (-7000 4800);
FORCEPROP 1 LASTPIN (-7550 4750) $PN 1
J 0
(-7538 4762);
DISPLAY 0.787234 (-7538 4762);
PAINT MONO (-7538 4762);
FORCEPROP 1 LASTPIN (-7350 4750) $PN 2
J 0
(-7388 4762);
DISPLAY 0.787234 (-7388 4762);
PAINT MONO (-7388 4762);
FORCEPROP 2 LAST ROOM USB3_HUB2_MRP
J 0
(-7575 4700);
DISPLAY 0.680851 (-7575 4700);
PAINT RED (-7575 4700);
FORCEPROP 1 LAST PACK_TYPE 0402LF
J 0
(-7200 4750);
DISPLAY 0.617021 (-7200 4750);
FORCEPROP 1 LAST MATERIAL CHIP
J 0
(-7000 4750);
DISPLAY 0.617021 (-7000 4750);
FORCEPROP 1 LAST TOLERANCE 5%
J 0
(-7275 4750);
DISPLAY 0.617021 (-7275 4750);
FORCEPROP 1 LAST VALUE 0
J 2
(-7300 4750);
DISPLAY 0.617021 (-7300 4750);
FORCEPROP 1 LAST WATTAGE 1/16W
J 2
(-7250 4700);
DISPLAY 0.617021 (-7250 4700);
DISPLAY INVISIBLE (-7250 4700);
FORCEPROP 2 LAST BOM_COST VR_SYSTEM 
J 0
(-7500 4900);
DISPLAY 0.680851 (-7500 4900);
DISPLAY INVISIBLE (-7500 4900);
FORCEPROP 2 LAST CDS_LIB pure_quanta
J 0
(-7450 4750);
DISPLAY INVISIBLE (-7450 4750);
FORCEPROP 1 LAST PATH I150
J 0
(-7500 4900);
DISPLAY 0.978723 (-7500 4900);
PAINT WHITE (-7500 4900);
DISPLAY INVISIBLE (-7500 4900);
FORCEPROP 1 LAST PART_NUMBER CS00002JB13
J 0
(-7600 4800);
DISPLAY 0.617021 (-7600 4800);
DISPLAY INVISIBLE (-7600 4800);
FORCEADD Q_RES..1
(-7450 4925);
FORCEPROP 1 LAST LOCATION R6304
J 0
(-7725 4925);
DISPLAY 0.808511 (-7725 4925);
FORCEPROP 0 LAST $SEC 1
J 0
(-7575 5025);
DISPLAY 0.680851 (-7575 5025);
PAINT MONO (-7575 5025);
DISPLAY INVISIBLE (-7575 5025);
FORCEPROP 0 LAST CDS_SEC 1
J 0
(-7575 5025);
DISPLAY 0.680851 (-7575 5025);
DISPLAY INVISIBLE (-7575 5025);
FORCEPROP 1 LASTPIN (-7550 4925) $PN 1
J 0
(-7538 4937);
DISPLAY 0.787234 (-7538 4937);
PAINT MONO (-7538 4937);
FORCEPROP 1 LASTPIN (-7350 4925) $PN 2
J 0
(-7388 4937);
DISPLAY 0.787234 (-7388 4937);
PAINT MONO (-7388 4937);
FORCEPROP 1 LAST MATERIAL CHIP
J 0
(-7000 4925);
DISPLAY 0.617021 (-7000 4925);
FORCEPROP 2 LAST ROOM USB3_HUB2_TI
J 0
(-7575 5000);
DISPLAY 0.553191 (-7575 5000);
PAINT RED (-7575 5000);
FORCEPROP 1 LAST PACK_TYPE 0402LF
J 0
(-7200 4925);
DISPLAY 0.617021 (-7200 4925);
FORCEPROP 1 LAST TOLERANCE 5%
J 0
(-7275 4925);
DISPLAY 0.617021 (-7275 4925);
FORCEPROP 1 LAST VALUE 0
J 2
(-7300 4925);
DISPLAY 0.617021 (-7300 4925);
FORCEPROP 1 LAST WATTAGE 1/16W
J 2
(-7250 4875);
DISPLAY 0.617021 (-7250 4875);
DISPLAY INVISIBLE (-7250 4875);
FORCEPROP 2 LAST BOM_COST VR_SYSTEM 
J 0
(-7500 5075);
DISPLAY 0.680851 (-7500 5075);
DISPLAY INVISIBLE (-7500 5075);
FORCEPROP 2 LAST CDS_LIB pure_quanta
J 0
(-7450 4925);
DISPLAY INVISIBLE (-7450 4925);
FORCEPROP 1 LAST PATH I151
J 0
(-7500 5075);
DISPLAY 0.978723 (-7500 5075);
PAINT WHITE (-7500 5075);
DISPLAY INVISIBLE (-7500 5075);
FORCEPROP 1 LAST PART_NUMBER CS00002JB13
J 0
(-7600 4975);
DISPLAY 0.617021 (-7600 4975);
DISPLAY INVISIBLE (-7600 4975);
FORCEADD UNIVERSAL_POWER..1
(-8700 4800);
FORCEPROP 3 LASTPIN (-8700 4750) SIG_NAME P3V3_AUX\g
J 0
(-8690 4760);
DISPLAY 0.659574 (-8690 4760);
PAINT MONO (-8690 4760);
DISPLAY INVISIBLE (-8690 4760);
FORCEPROP 1 LAST HDL_POWER P3V3_AUX
J 1
(-8700 4850);
DISPLAY 0.489362 (-8700 4850);
PAINT GREEN (-8700 4850);
FORCEPROP 2 LAST BOM_COST VR_SYSTEM
J 0
(-8700 4900);
DISPLAY 0.617021 (-8700 4900);
PAINT PURPLE (-8700 4900);
DISPLAY INVISIBLE (-8700 4900);
FORCEPROP 2 LAST CDS_LIB pure_quanta_power
J 0
(-8700 4800);
DISPLAY INVISIBLE (-8700 4800);
FORCEPROP 1 LAST PATH I152
J 0
(-8650 4825);
DISPLAY 0.872340 (-8650 4825);
PAINT AQUA (-8650 4825);
DISPLAY INVISIBLE (-8650 4825);
FORCEADD Q_RES..2
(-8700 4550);
FORCEPROP 1 LAST LOCATION R6308
J 0
(-8655 4675);
DISPLAY 0.638298 (-8655 4675);
FORCEPROP 0 LAST $SEC 1
J 0
(-8650 4775);
DISPLAY 0.680851 (-8650 4775);
PAINT MONO (-8650 4775);
DISPLAY INVISIBLE (-8650 4775);
FORCEPROP 0 LAST CDS_SEC 1
J 0
(-8650 4775);
DISPLAY 0.680851 (-8650 4775);
DISPLAY INVISIBLE (-8650 4775);
FORCEPROP 1 LASTPIN (-8700 4650) $PN 1
J 0
(-8695 4612);
DISPLAY 0.787234 (-8695 4612);
PAINT MONO (-8695 4612);
FORCEPROP 1 LASTPIN (-8700 4450) $PN 2
J 0
(-8695 4460);
DISPLAY 0.787234 (-8695 4460);
PAINT MONO (-8695 4460);
FORCEPROP 1 LAST MATERIAL EMPTY
J 0
(-8660 4475);
DISPLAY 0.638298 (-8660 4475);
FORCEPROP 1 LAST WATTAGE 1/16W
J 0
(-8660 4525);
DISPLAY 0.638298 (-8660 4525);
FORCEPROP 1 LAST VALUE 200K
J 0
(-8655 4625);
DISPLAY 0.638298 (-8655 4625);
FORCEPROP 1 LAST TOLERANCE 1%
J 0
(-8655 4575);
DISPLAY 0.638298 (-8655 4575);
FORCEPROP 1 LAST PACK_TYPE 0402LF
J 0
(-8675 4425);
DISPLAY 0.638298 (-8675 4425);
FORCEPROP 2 LAST ROOM USB3_HUB2_MRP
J 0
(-8650 4725);
DISPLAY 0.553191 (-8650 4725);
PAINT RED (-8650 4725);
FORCEPROP 2 LAST CDS_LIB pure_quanta
J 0
(-8700 4550);
DISPLAY INVISIBLE (-8700 4550);
FORCEPROP 1 LAST PATH I153
J 0
(-8650 4725);
DISPLAY 0.978723 (-8650 4725);
PAINT WHITE (-8650 4725);
DISPLAY INVISIBLE (-8650 4725);
FORCEPROP 1 LAST PART_NUMBER CS42002FB05
J 0
(-8660 4425);
DISPLAY 0.638298 (-8660 4425);
DISPLAY INVISIBLE (-8660 4425);
FORCEADD UNIVERSAL_POWER..1
(-9125 5350);
FORCEPROP 3 LASTPIN (-9125 5300) SIG_NAME P3V3_AUX\g
J 0
(-9115 5310);
DISPLAY 0.659574 (-9115 5310);
PAINT MONO (-9115 5310);
DISPLAY INVISIBLE (-9115 5310);
FORCEPROP 1 LAST HDL_POWER P3V3_AUX
J 1
(-9125 5400);
DISPLAY 0.489362 (-9125 5400);
PAINT GREEN (-9125 5400);
FORCEPROP 2 LAST BOM_COST VR_SYSTEM
J 0
(-9125 5450);
DISPLAY 0.617021 (-9125 5450);
PAINT PURPLE (-9125 5450);
DISPLAY INVISIBLE (-9125 5450);
FORCEPROP 2 LAST CDS_LIB pure_quanta_power
J 0
(-9125 5350);
DISPLAY INVISIBLE (-9125 5350);
FORCEPROP 1 LAST PATH I154
J 0
(-9075 5375);
DISPLAY 0.872340 (-9075 5375);
PAINT AQUA (-9075 5375);
DISPLAY INVISIBLE (-9075 5375);
FORCEADD Q_RES..2
(-9125 5150);
FORCEPROP 1 LAST LOCATION R6306
J 0
(-9080 5275);
DISPLAY 0.638298 (-9080 5275);
FORCEPROP 0 LAST $SEC 1
J 0
(-9075 5325);
DISPLAY 0.680851 (-9075 5325);
PAINT MONO (-9075 5325);
DISPLAY INVISIBLE (-9075 5325);
FORCEPROP 0 LAST CDS_SEC 1
J 0
(-9075 5325);
DISPLAY 0.680851 (-9075 5325);
DISPLAY INVISIBLE (-9075 5325);
FORCEPROP 1 LASTPIN (-9125 5250) $PN 1
J 0
(-9120 5212);
DISPLAY 0.787234 (-9120 5212);
PAINT MONO (-9120 5212);
FORCEPROP 1 LASTPIN (-9125 5050) $PN 2
J 0
(-9120 5060);
DISPLAY 0.787234 (-9120 5060);
PAINT MONO (-9120 5060);
FORCEPROP 2 LAST ROOM USB3_HUB2_TI
J 0
(-9100 4975);
DISPLAY 0.553191 (-9100 4975);
PAINT RED (-9100 4975);
FORCEPROP 1 LAST TOLERANCE 1%
J 0
(-9080 5175);
DISPLAY 0.638298 (-9080 5175);
FORCEPROP 1 LAST MATERIAL CHIP
J 0
(-9085 5075);
DISPLAY 0.638298 (-9085 5075);
FORCEPROP 1 LAST WATTAGE 1/16W
J 0
(-9085 5125);
DISPLAY 0.638298 (-9085 5125);
FORCEPROP 1 LAST VALUE 4.7K
J 0
(-9080 5225);
DISPLAY 0.638298 (-9080 5225);
FORCEPROP 1 LAST PACK_TYPE 0402LF
J 0
(-9075 5025);
DISPLAY 0.638298 (-9075 5025);
FORCEPROP 2 LAST CDS_LIB pure_quanta
J 0
(-9125 5150);
DISPLAY INVISIBLE (-9125 5150);
FORCEPROP 1 LAST PATH I155
J 0
(-9075 5325);
DISPLAY 0.978723 (-9075 5325);
PAINT WHITE (-9075 5325);
DISPLAY INVISIBLE (-9075 5325);
FORCEPROP 1 LAST PART_NUMBER CS24702FB06
J 0
(-9085 5025);
DISPLAY 0.638298 (-9085 5025);
DISPLAY INVISIBLE (-9085 5025);
FORCEADD Q_RES..2
(-9125 4725);
FORCEPROP 1 LAST LOCATION R6307
J 0
(-9080 4850);
DISPLAY 0.638298 (-9080 4850);
FORCEPROP 0 LAST $SEC 1
J 0
(-9075 4900);
DISPLAY 0.680851 (-9075 4900);
PAINT MONO (-9075 4900);
DISPLAY INVISIBLE (-9075 4900);
FORCEPROP 0 LAST CDS_SEC 1
J 0
(-9075 4900);
DISPLAY 0.680851 (-9075 4900);
DISPLAY INVISIBLE (-9075 4900);
FORCEPROP 1 LASTPIN (-9125 4825) $PN 1
J 0
(-9120 4787);
DISPLAY 0.787234 (-9120 4787);
PAINT MONO (-9120 4787);
FORCEPROP 1 LASTPIN (-9125 4625) $PN 2
J 0
(-9120 4635);
DISPLAY 0.787234 (-9120 4635);
PAINT MONO (-9120 4635);
FORCEPROP 2 LAST ROOM USB3_HUB2_TI
J 0
(-9100 4550);
DISPLAY 0.553191 (-9100 4550);
PAINT RED (-9100 4550);
FORCEPROP 1 LAST WATTAGE 1/16W
J 0
(-9085 4700);
DISPLAY 0.638298 (-9085 4700);
FORCEPROP 1 LAST VALUE 4.7K
J 0
(-9080 4800);
DISPLAY 0.638298 (-9080 4800);
FORCEPROP 1 LAST TOLERANCE 1%
J 0
(-9080 4750);
DISPLAY 0.638298 (-9080 4750);
FORCEPROP 1 LAST MATERIAL EMPTY
J 0
(-9085 4650);
DISPLAY 0.638298 (-9085 4650);
FORCEPROP 1 LAST PACK_TYPE 0402LF
J 0
(-9075 4600);
DISPLAY 0.638298 (-9075 4600);
FORCEPROP 2 LAST CDS_LIB pure_quanta
J 0
(-9125 4725);
DISPLAY INVISIBLE (-9125 4725);
FORCEPROP 1 LAST PATH I156
J 0
(-9075 4900);
DISPLAY 0.978723 (-9075 4900);
PAINT WHITE (-9075 4900);
DISPLAY INVISIBLE (-9075 4900);
FORCEPROP 1 LAST PART_NUMBER CS24702FB06
J 0
(-9085 4600);
DISPLAY 0.638298 (-9085 4600);
DISPLAY INVISIBLE (-9085 4600);
FORCEADD GND..1
(-9125 4400);
FORCEPROP 3 LASTPIN (-9125 4450) SIG_NAME GND\g
J 0
(-9115 4460);
DISPLAY 0.659574 (-9115 4460);
PAINT MONO (-9115 4460);
DISPLAY INVISIBLE (-9115 4460);
FORCEPROP 1 LAST SIZE 1B
J 0
(-9050 4350);
DISPLAY 1.170213 (-9050 4350);
PAINT AQUA (-9050 4350);
DISPLAY INVISIBLE (-9050 4350);
FORCEPROP 2 LAST CDS_LIB pure_quanta_power
J 0
(-9125 4400);
DISPLAY INVISIBLE (-9125 4400);
FORCEPROP 1 LAST HDL_POWER GND
J 0
(-9125 4550);
DISPLAY 1.170213 (-9125 4550);
PAINT GREEN (-9125 4550);
DISPLAY INVISIBLE (-9125 4550);
FORCEPROP 1 LAST PATH I157
J 0
(-9050 4400);
DISPLAY 0.872340 (-9050 4400);
PAINT AQUA (-9050 4400);
DISPLAY INVISIBLE (-9050 4400);
FORCEADD Q_RES..2
(-8700 4050);
FORCEPROP 1 LAST LOCATION R6309
J 0
(-8650 4200);
DISPLAY 0.638298 (-8650 4200);
FORCEPROP 0 LAST $SEC 1
J 0
(-8650 4300);
DISPLAY 0.680851 (-8650 4300);
PAINT MONO (-8650 4300);
DISPLAY INVISIBLE (-8650 4300);
FORCEPROP 0 LAST CDS_SEC 1
J 0
(-8650 4300);
DISPLAY 0.680851 (-8650 4300);
DISPLAY INVISIBLE (-8650 4300);
FORCEPROP 1 LASTPIN (-8700 4150) $PN 1
J 0
(-8695 4112);
DISPLAY 0.787234 (-8695 4112);
PAINT MONO (-8695 4112);
FORCEPROP 1 LASTPIN (-8700 3950) $PN 2
J 0
(-8695 3960);
DISPLAY 0.787234 (-8695 3960);
PAINT MONO (-8695 3960);
FORCEPROP 1 LAST PACK_TYPE 0402LF
J 0
(-8650 3975);
DISPLAY 0.510638 (-8650 3975);
FORCEPROP 1 LAST WATTAGE 1/16W
J 0
(-8650 4050);
DISPLAY 0.510638 (-8650 4050);
FORCEPROP 1 LAST VALUE 200K
J 0
(-8650 4150);
DISPLAY 0.510638 (-8650 4150);
FORCEPROP 1 LAST TOLERANCE 1%
J 0
(-8650 4100);
DISPLAY 0.510638 (-8650 4100);
FORCEPROP 1 LAST MATERIAL CHIP
J 0
(-8650 4000);
DISPLAY 0.510638 (-8650 4000);
FORCEPROP 2 LAST ROOM USB3_HUB2_MRP
J 0
(-9075 4050);
DISPLAY 0.553191 (-9075 4050);
PAINT RED (-9075 4050);
FORCEPROP 2 LAST CDS_LIB pure_quanta
J 0
(-8700 4050);
DISPLAY INVISIBLE (-8700 4050);
FORCEPROP 1 LAST PATH I158
J 0
(-8650 4225);
DISPLAY 0.978723 (-8650 4225);
PAINT WHITE (-8650 4225);
DISPLAY INVISIBLE (-8650 4225);
FORCEPROP 1 LAST PART_NUMBER CS42002FB05
J 0
(-8650 3950);
DISPLAY 0.510638 (-8650 3950);
DISPLAY INVISIBLE (-8650 3950);
FORCEADD GND..1
(-8700 3850);
FORCEPROP 3 LASTPIN (-8700 3900) SIG_NAME GND\g
J 0
(-8690 3910);
DISPLAY 0.659574 (-8690 3910);
PAINT MONO (-8690 3910);
DISPLAY INVISIBLE (-8690 3910);
FORCEPROP 1 LAST SIZE 1B
J 0
(-8625 3800);
DISPLAY 1.170213 (-8625 3800);
PAINT AQUA (-8625 3800);
DISPLAY INVISIBLE (-8625 3800);
FORCEPROP 2 LAST CDS_LIB pure_quanta_power
J 0
(-8700 3850);
DISPLAY INVISIBLE (-8700 3850);
FORCEPROP 1 LAST HDL_POWER GND
J 0
(-8700 4000);
DISPLAY 1.170213 (-8700 4000);
PAINT GREEN (-8700 4000);
DISPLAY INVISIBLE (-8700 4000);
FORCEPROP 1 LAST PATH I159
J 0
(-8625 3850);
DISPLAY 0.872340 (-8625 3850);
PAINT AQUA (-8625 3850);
DISPLAY INVISIBLE (-8625 3850);
FORCEADD Q_RES..1
(-6925 3475);
FORCEPROP 1 LAST LOCATION R6257
J 0
(-7150 3475);
DISPLAY 0.638298 (-7150 3475);
FORCEPROP 0 LAST $SEC 1
J 0
(-6750 3550);
DISPLAY 0.680851 (-6750 3550);
PAINT MONO (-6750 3550);
DISPLAY INVISIBLE (-6750 3550);
FORCEPROP 0 LAST CDS_SEC 1
J 0
(-6750 3550);
DISPLAY 0.680851 (-6750 3550);
DISPLAY INVISIBLE (-6750 3550);
FORCEPROP 1 LASTPIN (-7025 3475) $PN 1
J 0
(-7013 3487);
DISPLAY 0.787234 (-7013 3487);
PAINT MONO (-7013 3487);
FORCEPROP 1 LASTPIN (-6825 3475) $PN 2
J 0
(-6863 3487);
DISPLAY 0.787234 (-6863 3487);
PAINT MONO (-6863 3487);
FORCEPROP 0 LAST ROOM USB3_HUB2
J 0
(-6750 3600);
DISPLAY 0.680851 (-6750 3600);
PAINT RED (-6750 3600);
FORCEPROP 1 LAST VALUE 1M
J 2
(-6750 3475);
DISPLAY 0.510638 (-6750 3475);
FORCEPROP 1 LAST MATERIAL CHIP
J 0
(-6750 3525);
DISPLAY 0.510638 (-6750 3525);
FORCEPROP 1 LAST TOLERANCE 1%
J 0
(-6725 3475);
DISPLAY 0.510638 (-6725 3475);
FORCEPROP 1 LAST WATTAGE 1/16W
J 2
(-7000 3525);
DISPLAY 0.510638 (-7000 3525);
FORCEPROP 1 LAST PACK_TYPE 0402LF
J 0
(-6650 3475);
DISPLAY 0.510638 (-6650 3475);
FORCEPROP 2 LAST CDS_LIB pure_quanta
J 0
(-6925 3475);
DISPLAY INVISIBLE (-6925 3475);
FORCEPROP 1 LAST PATH I160
J 0
(-6975 3625);
DISPLAY 0.978723 (-6975 3625);
PAINT WHITE (-6975 3625);
DISPLAY INVISIBLE (-6975 3625);
FORCEPROP 1 LAST PART_NUMBER CS51002FB05
J 0
(-6975 3525);
DISPLAY 0.404255 (-6975 3525);
DISPLAY INVISIBLE (-6975 3525);
FORCEADD GND..1
(-6250 2625);
FORCEPROP 3 LASTPIN (-6250 2675) SIG_NAME GND\g
J 0
(-6240 2685);
DISPLAY 0.659574 (-6240 2685);
PAINT MONO (-6240 2685);
DISPLAY INVISIBLE (-6240 2685);
FORCEPROP 2 LAST CDS_LIB pure_quanta_power
J 0
(-6250 2625);
DISPLAY INVISIBLE (-6250 2625);
FORCEPROP 1 LAST SIZE 1B
J 0
(-6175 2575);
DISPLAY 1.170213 (-6175 2575);
PAINT AQUA (-6175 2575);
DISPLAY INVISIBLE (-6175 2575);
FORCEPROP 1 LAST HDL_POWER GND
J 0
(-6250 2775);
DISPLAY 1.170213 (-6250 2775);
PAINT GREEN (-6250 2775);
DISPLAY INVISIBLE (-6250 2775);
FORCEPROP 1 LAST PATH I162
J 0
(-6175 2625);
DISPLAY 0.872340 (-6175 2625);
PAINT AQUA (-6175 2625);
DISPLAY INVISIBLE (-6175 2625);
FORCEADD GND..1
(-6500 2650);
FORCEPROP 3 LASTPIN (-6500 2700) SIG_NAME GND\g
J 0
(-6490 2710);
DISPLAY 0.659574 (-6490 2710);
PAINT MONO (-6490 2710);
DISPLAY INVISIBLE (-6490 2710);
FORCEPROP 2 LAST CDS_LIB pure_quanta_power
J 0
(-6500 2650);
DISPLAY INVISIBLE (-6500 2650);
FORCEPROP 1 LAST SIZE 1B
J 0
(-6425 2600);
DISPLAY 1.170213 (-6425 2600);
PAINT AQUA (-6425 2600);
DISPLAY INVISIBLE (-6425 2600);
FORCEPROP 1 LAST HDL_POWER GND
J 0
(-6500 2800);
DISPLAY 1.170213 (-6500 2800);
PAINT GREEN (-6500 2800);
DISPLAY INVISIBLE (-6500 2800);
FORCEPROP 1 LAST PATH I163
J 0
(-6425 2650);
DISPLAY 0.872340 (-6425 2650);
PAINT AQUA (-6425 2650);
DISPLAY INVISIBLE (-6425 2650);
FORCEADD Q_XTAL_4P_13BI_24GND..1
R 2
(-6825 3050);
FORCEPROP 1 LAST LOCATION Y6000
J 2
(-6675 3325);
DISPLAY 0.723404 (-6675 3325);
PAINT GREEN (-6675 3325);
FORCEPROP 2 LAST SEC 1
J 2
(-6700 3550);
DISPLAY 0.680851 (-6700 3550);
PAINT MONO (-6700 3550);
DISPLAY INVISIBLE (-6700 3550);
FORCEPROP 2 LASTPIN (-6550 2925) $PN 2
J 0
(-6540 2935);
DISPLAY 0.680851 (-6540 2935);
PAINT MONO (-6540 2935);
FORCEPROP 2 LASTPIN (-7100 2925) $PN 4
J 2
(-7110 2935);
DISPLAY 0.680851 (-7110 2935);
PAINT MONO (-7110 2935);
FORCEPROP 2 LASTPIN (-6550 3125) $PN 1
J 0
(-6540 3135);
DISPLAY 0.680851 (-6540 3135);
PAINT MONO (-6540 3135);
FORCEPROP 2 LASTPIN (-7100 3125) $PN 3
J 2
(-7110 3135);
DISPLAY 0.680851 (-7110 3135);
PAINT MONO (-7110 3135);
FORCEPROP 1 LAST MATERIAL MISC
J 2
(-6692 3229);
DISPLAY 0.723404 (-6692 3229);
PAINT GREEN (-6692 3229);
FORCEPROP 2 LAST VALUE 24MHZ
J 2
(-6683 3359);
DISPLAY 0.680851 (-6683 3359);
FORCEPROP 2 LAST PART_TYPE SMLF
J 2
(-6683 3409);
DISPLAY 0.680851 (-6683 3409);
FORCEPROP 0 LAST ROOM USB3_HUB2
J 0
(-6650 3225);
DISPLAY 0.680851 (-6650 3225);
PAINT RED (-6650 3225);
FORCEPROP 2 LAST CDS_LIB pure_quanta
J 2
(-6825 3050);
DISPLAY INVISIBLE (-6825 3050);
FORCEPROP 1 LAST CDS_LMAN_SYM_OUTLINE -125,175,125,-175
J 2
(-6825 3050);
DISPLAY 0.468085 (-6825 3050);
PAINT GREEN (-6825 3050);
DISPLAY INVISIBLE (-6825 3050);
FORCEPROP 1 LAST PIN_NAMES_ROTATE True
J 2
(-6825 3050);
DISPLAY 0.489362 (-6825 3050);
PAINT GREEN (-6825 3050);
DISPLAY INVISIBLE (-6825 3050);
FORCEPROP 2 LAST SEC_TYPE 
J 2
(-6700 3550);
DISPLAY 0.680851 (-6700 3550);
DISPLAY INVISIBLE (-6700 3550);
FORCEPROP 1 LAST PATH I164
J 2
(-6950 2875);
DISPLAY 0.723404 (-6950 2875);
PAINT GREEN (-6950 2875);
DISPLAY INVISIBLE (-6950 2875);
FORCEPROP 1 LAST PART_NUMBER BG624000101
J 2
(-6675 3275);
DISPLAY 0.723404 (-6675 3275);
PAINT GREEN (-6675 3275);
DISPLAY INVISIBLE (-6675 3275);
FORCEADD GND..1
(-7375 2650);
FORCEPROP 3 LASTPIN (-7375 2700) SIG_NAME GND\g
J 0
(-7365 2710);
DISPLAY 0.659574 (-7365 2710);
PAINT MONO (-7365 2710);
DISPLAY INVISIBLE (-7365 2710);
FORCEPROP 1 LAST SIZE 1B
J 0
(-7300 2600);
DISPLAY 1.170213 (-7300 2600);
PAINT AQUA (-7300 2600);
DISPLAY INVISIBLE (-7300 2600);
FORCEPROP 2 LAST CDS_LIB pure_quanta_power
J 0
(-7375 2650);
DISPLAY INVISIBLE (-7375 2650);
FORCEPROP 1 LAST HDL_POWER GND
J 0
(-7375 2800);
DISPLAY 1.170213 (-7375 2800);
PAINT GREEN (-7375 2800);
DISPLAY INVISIBLE (-7375 2800);
FORCEPROP 1 LAST PATH I166
J 0
(-7300 2650);
DISPLAY 0.872340 (-7300 2650);
PAINT AQUA (-7300 2650);
DISPLAY INVISIBLE (-7300 2650);
FORCEADD GND..1
(-7200 2650);
FORCEPROP 3 LASTPIN (-7200 2700) SIG_NAME GND\g
J 0
(-7190 2710);
DISPLAY 0.659574 (-7190 2710);
PAINT MONO (-7190 2710);
DISPLAY INVISIBLE (-7190 2710);
FORCEPROP 1 LAST SIZE 1B
J 0
(-7125 2600);
DISPLAY 1.170213 (-7125 2600);
PAINT AQUA (-7125 2600);
DISPLAY INVISIBLE (-7125 2600);
FORCEPROP 2 LAST CDS_LIB pure_quanta_power
J 0
(-7200 2650);
DISPLAY INVISIBLE (-7200 2650);
FORCEPROP 1 LAST HDL_POWER GND
J 0
(-7200 2800);
DISPLAY 1.170213 (-7200 2800);
PAINT GREEN (-7200 2800);
DISPLAY INVISIBLE (-7200 2800);
FORCEPROP 1 LAST PATH I167
J 0
(-7125 2650);
DISPLAY 0.872340 (-7125 2650);
PAINT AQUA (-7125 2650);
DISPLAY INVISIBLE (-7125 2650);
FORCEADD OFFPAGE..1
(-6850 4625);
FORCEPROP 2 LAST $XR0 179 
J 0
(-7102 4625);
DISPLAY 0.638298 (-7102 4625);
PAINT MONO (-7102 4625);
FORCEPROP 2 LAST CDS_LIB standard
J 0
(-6850 4625);
DISPLAY INVISIBLE (-6850 4625);
FORCEPROP 1 LAST OFFPAGE TRUE
J 0
(-6525 4500);
DISPLAY 0.872340 (-6525 4500);
PAINT GREEN (-6525 4500);
DISPLAY INVISIBLE (-6525 4500);
FORCEPROP 1 LAST COMMENT_BODY TRUE
J 0
(-6725 4525);
DISPLAY 0.872340 (-6725 4525);
PAINT GREEN (-6725 4525);
DISPLAY INVISIBLE (-6725 4525);
FORCEPROP 2 LAST PATH I168
J 2
(-7050 4675);
DISPLAY 0.680851 (-7050 4675);
DISPLAY INVISIBLE (-7050 4675);
FORCEADD UNIVERSAL_POWER..1
(-2750 3625);
FORCEPROP 3 LASTPIN (-2750 3575) SIG_NAME P3V3_AUX_CPU0_USB2_AVDD33\g
J 0
(-2740 3585);
DISPLAY 0.659574 (-2740 3585);
PAINT MONO (-2740 3585);
DISPLAY INVISIBLE (-2740 3585);
FORCEPROP 1 LAST HDL_POWER P3V3_AUX_CPU0_USB2_AVDD33
J 1
(-2750 3675);
DISPLAY 0.489362 (-2750 3675);
PAINT GREEN (-2750 3675);
FORCEPROP 2 LAST BOM_COST VR_SYSTEM
J 0
(-2750 3725);
DISPLAY 0.617021 (-2750 3725);
PAINT PURPLE (-2750 3725);
DISPLAY INVISIBLE (-2750 3725);
FORCEPROP 2 LAST CDS_LIB pure_quanta_power
J 0
(-2750 3625);
DISPLAY INVISIBLE (-2750 3625);
FORCEPROP 1 LAST PATH I169
J 0
(-2700 3650);
DISPLAY 0.872340 (-2700 3650);
PAINT AQUA (-2700 3650);
DISPLAY INVISIBLE (-2700 3650);
FORCEADD Q_INDUCTOR..1
(-6200 2000);
FORCEPROP 1 LAST LOCATION L6003
J 0
(-6325 2160);
DISPLAY 0.723404 (-6325 2160);
PAINT GREEN (-6325 2160);
FORCEPROP 0 LAST $SEC 1
J 0
(-6325 2300);
DISPLAY 0.680851 (-6325 2300);
PAINT MONO (-6325 2300);
DISPLAY INVISIBLE (-6325 2300);
FORCEPROP 0 LAST CDS_SEC 1
J 0
(-6325 2300);
DISPLAY 0.680851 (-6325 2300);
DISPLAY INVISIBLE (-6325 2300);
FORCEPROP 0 LASTPIN (-6300 1975) $PN 1
J 2
(-6310 1985);
DISPLAY 0.680851 (-6310 1985);
PAINT MONO (-6310 1985);
FORCEPROP 0 LASTPIN (-6100 1975) $PN 2
J 0
(-6090 1985);
DISPLAY 0.680851 (-6090 1985);
PAINT MONO (-6090 1985);
FORCEPROP 2 LAST PACK_TYPE SMLF
J 0
(-6325 2200);
DISPLAY 0.680851 (-6325 2200);
FORCEPROP 1 LAST MATERIAL IND
J 0
(-6325 2055);
DISPLAY 0.723404 (-6325 2055);
PAINT GREEN (-6325 2055);
FORCEPROP 2 LAST VALUE BLM21PG221SN1D
J 0
(-6325 2250);
DISPLAY 0.680851 (-6325 2250);
FORCEPROP 0 LAST ROOM USB3_HUB2
J 0
(-6325 2350);
DISPLAY 0.680851 (-6325 2350);
PAINT RED (-6325 2350);
FORCEPROP 1 LAST NEEDS_NO_SIZE TRUE
J 0
(-6200 2000);
DISPLAY 0.468085 (-6200 2000);
PAINT GREEN (-6200 2000);
DISPLAY INVISIBLE (-6200 2000);
FORCEPROP 2 LAST CDS_LIB pure_quanta
J 0
(-6200 2000);
DISPLAY INVISIBLE (-6200 2000);
FORCEPROP 1 LAST PATH I17
J 0
(-6125 2055);
DISPLAY 0.723404 (-6125 2055);
PAINT GREEN (-6125 2055);
DISPLAY INVISIBLE (-6125 2055);
FORCEPROP 1 LAST PART_NUMBER CX1PG221001
J 0
(-6325 2110);
DISPLAY 0.723404 (-6325 2110);
PAINT GREEN (-6325 2110);
DISPLAY INVISIBLE (-6325 2110);
FORCEADD Q_RES..1
(-2150 5675);
FORCEPROP 1 LAST LOCATION R6260
J 0
(-2425 5675);
DISPLAY 0.808511 (-2425 5675);
FORCEPROP 0 LAST $SEC 1
J 0
(-2225 5775);
DISPLAY 0.680851 (-2225 5775);
PAINT MONO (-2225 5775);
DISPLAY INVISIBLE (-2225 5775);
FORCEPROP 0 LAST CDS_SEC 1
J 0
(-2225 5775);
DISPLAY 0.680851 (-2225 5775);
DISPLAY INVISIBLE (-2225 5775);
FORCEPROP 1 LASTPIN (-2250 5675) $PN 1
J 0
(-2238 5687);
DISPLAY 0.787234 (-2238 5687);
PAINT MONO (-2238 5687);
FORCEPROP 1 LASTPIN (-2050 5675) $PN 2
J 0
(-2088 5687);
DISPLAY 0.787234 (-2088 5687);
PAINT MONO (-2088 5687);
FORCEPROP 1 LAST MATERIAL CHIP
J 0
(-1700 5675);
DISPLAY 0.617021 (-1700 5675);
FORCEPROP 1 LAST PACK_TYPE 0402LF
J 0
(-1900 5675);
DISPLAY 0.617021 (-1900 5675);
FORCEPROP 2 LAST ROOM USB3_HUB2_TI
J 0
(-2325 5750);
DISPLAY 0.680851 (-2325 5750);
PAINT RED (-2325 5750);
FORCEPROP 1 LAST VALUE 0
J 2
(-2000 5675);
DISPLAY 0.617021 (-2000 5675);
FORCEPROP 1 LAST TOLERANCE 5%
J 0
(-1975 5675);
DISPLAY 0.617021 (-1975 5675);
FORCEPROP 1 LAST WATTAGE 1/16W
J 2
(-1950 5625);
DISPLAY 0.617021 (-1950 5625);
DISPLAY INVISIBLE (-1950 5625);
FORCEPROP 2 LAST BOM_COST VR_SYSTEM 
J 0
(-2200 5825);
DISPLAY 0.680851 (-2200 5825);
DISPLAY INVISIBLE (-2200 5825);
FORCEPROP 2 LAST CDS_LIB pure_quanta
J 0
(-2150 5675);
DISPLAY INVISIBLE (-2150 5675);
FORCEPROP 1 LAST PATH I170
J 0
(-2200 5825);
DISPLAY 0.978723 (-2200 5825);
PAINT WHITE (-2200 5825);
DISPLAY INVISIBLE (-2200 5825);
FORCEPROP 1 LAST PART_NUMBER CS00002JB13
J 0
(-2300 5725);
DISPLAY 0.617021 (-2300 5725);
DISPLAY INVISIBLE (-2300 5725);
FORCEADD Q_RES..2
(-8200 3500);
FORCEPROP 1 LAST LOCATION R6284
J 0
(-8150 3625);
DISPLAY 0.638298 (-8150 3625);
FORCEPROP 2 LAST SEC 1
J 0
(-8150 3725);
DISPLAY 0.680851 (-8150 3725);
PAINT MONO (-8150 3725);
DISPLAY INVISIBLE (-8150 3725);
FORCEPROP 1 LASTPIN (-8200 3600) $PN 1
J 0
(-8195 3562);
DISPLAY 0.787234 (-8195 3562);
PAINT MONO (-8195 3562);
FORCEPROP 1 LASTPIN (-8200 3400) $PN 2
J 0
(-8195 3410);
DISPLAY 0.787234 (-8195 3410);
PAINT MONO (-8195 3410);
FORCEPROP 0 LAST ROOM USB3_HUB2_TI
J 0
(-8150 3275);
DISPLAY 0.680851 (-8150 3275);
PAINT RED (-8150 3275);
FORCEPROP 1 LAST TOLERANCE 1%
J 0
(-8155 3525);
DISPLAY 0.638298 (-8155 3525);
FORCEPROP 1 LAST MATERIAL CHIP
J 0
(-8160 3425);
DISPLAY 0.638298 (-8160 3425);
FORCEPROP 1 LAST PACK_TYPE 0402LF
J 0
(-8160 3325);
DISPLAY 0.638298 (-8160 3325);
FORCEPROP 1 LAST WATTAGE 1/16W
J 0
(-8160 3475);
DISPLAY 0.638298 (-8160 3475);
FORCEPROP 1 LAST VALUE 10
J 0
(-8155 3575);
DISPLAY 0.638298 (-8155 3575);
FORCEPROP 2 LAST CDS_LIB pure_quanta
J 0
(-8200 3500);
DISPLAY INVISIBLE (-8200 3500);
FORCEPROP 2 LAST SEC_TYPE 0402LF
J 0
(-8150 3725);
DISPLAY 0.680851 (-8150 3725);
DISPLAY INVISIBLE (-8150 3725);
FORCEPROP 1 LAST PATH I171
J 0
(-8150 3675);
DISPLAY 0.978723 (-8150 3675);
PAINT WHITE (-8150 3675);
DISPLAY INVISIBLE (-8150 3675);
FORCEPROP 1 LAST PART_NUMBER CS01002FB07
J 0
(-8160 3375);
DISPLAY 0.638298 (-8160 3375);
DISPLAY INVISIBLE (-8160 3375);
FORCEADD Q_CAP..1
R 2
(-7375 2900);
FORCEPROP 1 LAST LOCATION C6090
J 2
(-7425 3000);
DISPLAY 0.978723 (-7425 3000);
FORCEPROP 2 LAST SEC 1
J 0
(-7425 3100);
DISPLAY 0.680851 (-7425 3100);
PAINT MONO (-7425 3100);
DISPLAY INVISIBLE (-7425 3100);
FORCEPROP 1 LASTPIN (-7375 3000) $PN 1
J 2
(-7385 2980);
DISPLAY 0.787234 (-7385 2980);
PAINT MONO (-7385 2980);
FORCEPROP 1 LASTPIN (-7375 2800) $PN 2
J 2
(-7385 2780);
DISPLAY 0.787234 (-7385 2780);
PAINT MONO (-7385 2780);
FORCEPROP 1 LAST MATERIAL NPO
J 2
(-7425 2800);
DISPLAY 0.978723 (-7425 2800);
FORCEPROP 1 LAST TOLERANCE 5%
J 2
(-7425 2850);
DISPLAY 0.978723 (-7425 2850);
FORCEPROP 1 LAST VALUE 27PF
J 2
(-7425 2950);
DISPLAY 0.978723 (-7425 2950);
FORCEPROP 1 LAST VOLTAGE 50V
J 2
(-7425 2900);
DISPLAY 0.978723 (-7425 2900);
FORCEPROP 1 LAST PACK_TYPE 0402
J 2
(-7425 2700);
DISPLAY 0.978723 (-7425 2700);
FORCEPROP 0 LAST ROOM USB3_HUB2
J 0
(-7725 3075);
DISPLAY 0.680851 (-7725 3075);
PAINT RED (-7725 3075);
FORCEPROP 2 LAST SEC_TYPE 0402
J 0
(-7425 3100);
DISPLAY 0.680851 (-7425 3100);
DISPLAY INVISIBLE (-7425 3100);
FORCEPROP 2 LAST CDS_LIB pure_quanta
J 2
(-7375 2900);
DISPLAY INVISIBLE (-7375 2900);
FORCEPROP 1 LAST PATH I174
J 2
(-7425 3050);
DISPLAY 0.978723 (-7425 3050);
PAINT WHITE (-7425 3050);
DISPLAY INVISIBLE (-7425 3050);
FORCEPROP 1 LAST PART_NUMBER CH02706JB06
J 2
(-7425 2750);
DISPLAY 0.978723 (-7425 2750);
DISPLAY INVISIBLE (-7425 2750);
FORCEADD Q_CAP..1
(-6250 2875);
FORCEPROP 1 LAST LOCATION C6091
J 0
(-6200 2975);
DISPLAY 0.978723 (-6200 2975);
FORCEPROP 2 LAST SEC 1
J 0
(-5900 3100);
DISPLAY 0.680851 (-5900 3100);
PAINT MONO (-5900 3100);
DISPLAY INVISIBLE (-5900 3100);
FORCEPROP 1 LASTPIN (-6250 2975) $PN 1
J 0
(-6240 2955);
DISPLAY 0.787234 (-6240 2955);
PAINT MONO (-6240 2955);
FORCEPROP 1 LASTPIN (-6250 2775) $PN 2
J 0
(-6240 2755);
DISPLAY 0.787234 (-6240 2755);
PAINT MONO (-6240 2755);
FORCEPROP 1 LAST PACK_TYPE 0402
J 0
(-6200 2675);
DISPLAY 0.978723 (-6200 2675);
FORCEPROP 1 LAST VALUE 27PF
J 0
(-6200 2925);
DISPLAY 0.978723 (-6200 2925);
FORCEPROP 1 LAST MATERIAL NPO
J 0
(-6200 2775);
DISPLAY 0.978723 (-6200 2775);
FORCEPROP 1 LAST VOLTAGE 50V
J 0
(-6200 2875);
DISPLAY 0.978723 (-6200 2875);
FORCEPROP 1 LAST TOLERANCE 5%
J 0
(-6200 2825);
DISPLAY 0.978723 (-6200 2825);
FORCEPROP 0 LAST ROOM USB3_HUB2
J 2
(-5900 3050);
DISPLAY 0.680851 (-5900 3050);
PAINT RED (-5900 3050);
FORCEPROP 2 LAST SEC_TYPE 0402
J 0
(-5900 3100);
DISPLAY 0.680851 (-5900 3100);
DISPLAY INVISIBLE (-5900 3100);
FORCEPROP 2 LAST CDS_LIB pure_quanta
J 2
(-6250 2875);
DISPLAY INVISIBLE (-6250 2875);
FORCEPROP 1 LAST PATH I175
J 0
(-6200 3025);
DISPLAY 0.978723 (-6200 3025);
PAINT WHITE (-6200 3025);
DISPLAY INVISIBLE (-6200 3025);
FORCEPROP 1 LAST PART_NUMBER CH02706JB06
J 0
(-6200 2725);
DISPLAY 0.978723 (-6200 2725);
DISPLAY INVISIBLE (-6200 2725);
FORCEADD UNIVERSAL_POWER..1
(-6650 2225);
FORCEPROP 3 LASTPIN (-6650 2175) SIG_NAME P3V3_AUX\g
J 0
(-6640 2185);
DISPLAY 0.659574 (-6640 2185);
PAINT MONO (-6640 2185);
DISPLAY INVISIBLE (-6640 2185);
FORCEPROP 1 LAST HDL_POWER P3V3_AUX
J 1
(-6650 2275);
DISPLAY 0.489362 (-6650 2275);
PAINT GREEN (-6650 2275);
FORCEPROP 2 LAST CDS_LIB pure_quanta_power
J 0
(-6650 2225);
DISPLAY INVISIBLE (-6650 2225);
FORCEPROP 2 LAST BOM_COST VR_SYSTEM
J 0
(-6650 2325);
DISPLAY 0.617021 (-6650 2325);
PAINT PURPLE (-6650 2325);
DISPLAY INVISIBLE (-6650 2325);
FORCEPROP 1 LAST PATH I18
J 0
(-6600 2250);
DISPLAY 0.872340 (-6600 2250);
PAINT AQUA (-6600 2250);
DISPLAY INVISIBLE (-6600 2250);
FORCEADD UNIVERSAL_POWER..1
(-5425 2225);
FORCEPROP 3 LASTPIN (-5425 2175) SIG_NAME P3V3_AUX_CPU0_USB2_AVDD33\g
J 0
(-5415 2185);
DISPLAY 0.659574 (-5415 2185);
PAINT MONO (-5415 2185);
DISPLAY INVISIBLE (-5415 2185);
FORCEPROP 1 LAST HDL_POWER P3V3_AUX_CPU0_USB2_AVDD33
J 1
(-5425 2275);
DISPLAY 0.489362 (-5425 2275);
PAINT GREEN (-5425 2275);
FORCEPROP 2 LAST BOM_COST VR_SYSTEM
J 0
(-5425 2325);
DISPLAY 0.617021 (-5425 2325);
PAINT PURPLE (-5425 2325);
DISPLAY INVISIBLE (-5425 2325);
FORCEPROP 2 LAST CDS_LIB pure_quanta_power
J 0
(-5425 2225);
DISPLAY INVISIBLE (-5425 2225);
FORCEPROP 1 LAST PATH I19
J 0
(-5375 2250);
DISPLAY 0.872340 (-5375 2250);
PAINT AQUA (-5375 2250);
DISPLAY INVISIBLE (-5375 2250);
FORCEADD Q_INDUCTOR..1
(-7900 1075);
FORCEPROP 1 LAST LOCATION L6004
J 0
(-8025 1235);
DISPLAY 0.723404 (-8025 1235);
PAINT GREEN (-8025 1235);
FORCEPROP 0 LAST $SEC 1
J 0
(-8025 1375);
DISPLAY 0.680851 (-8025 1375);
PAINT MONO (-8025 1375);
DISPLAY INVISIBLE (-8025 1375);
FORCEPROP 0 LAST CDS_SEC 1
J 0
(-8025 1375);
DISPLAY 0.680851 (-8025 1375);
DISPLAY INVISIBLE (-8025 1375);
FORCEPROP 0 LASTPIN (-8000 1050) $PN 1
J 2
(-8010 1060);
DISPLAY 0.680851 (-8010 1060);
PAINT MONO (-8010 1060);
FORCEPROP 0 LASTPIN (-7800 1050) $PN 2
J 0
(-7790 1060);
DISPLAY 0.680851 (-7790 1060);
PAINT MONO (-7790 1060);
FORCEPROP 2 LAST PACK_TYPE SMLF
J 0
(-8025 1275);
DISPLAY 0.680851 (-8025 1275);
FORCEPROP 1 LAST MATERIAL IND
J 0
(-8025 1130);
DISPLAY 0.723404 (-8025 1130);
PAINT GREEN (-8025 1130);
FORCEPROP 2 LAST VALUE BLM21PG221SN1D
J 0
(-8025 1325);
DISPLAY 0.680851 (-8025 1325);
FORCEPROP 0 LAST ROOM USB3_HUB2
J 0
(-8025 1425);
DISPLAY 0.680851 (-8025 1425);
PAINT RED (-8025 1425);
FORCEPROP 2 LAST CDS_LIB pure_quanta
J 0
(-7900 1075);
DISPLAY INVISIBLE (-7900 1075);
FORCEPROP 1 LAST NEEDS_NO_SIZE TRUE
J 0
(-7900 1075);
DISPLAY 0.468085 (-7900 1075);
PAINT GREEN (-7900 1075);
DISPLAY INVISIBLE (-7900 1075);
FORCEPROP 1 LAST PATH I20
J 0
(-7825 1130);
DISPLAY 0.723404 (-7825 1130);
PAINT GREEN (-7825 1130);
DISPLAY INVISIBLE (-7825 1130);
FORCEPROP 1 LAST PART_NUMBER CX1PG221001
J 0
(-8025 1185);
DISPLAY 0.723404 (-8025 1185);
PAINT GREEN (-8025 1185);
DISPLAY INVISIBLE (-8025 1185);
FORCEADD Q_CAP..1
(-5425 1675);
FORCEPROP 1 LAST LOCATION C6092
J 0
(-5375 1775);
DISPLAY 0.787234 (-5375 1775);
FORCEPROP 0 LAST $SEC 1
J 0
(-5375 1825);
DISPLAY 0.680851 (-5375 1825);
PAINT MONO (-5375 1825);
DISPLAY INVISIBLE (-5375 1825);
FORCEPROP 0 LAST CDS_SEC 1
J 0
(-5375 1825);
DISPLAY 0.680851 (-5375 1825);
DISPLAY INVISIBLE (-5375 1825);
FORCEPROP 1 LASTPIN (-5425 1775) $PN 1
J 0
(-5415 1755);
DISPLAY 0.787234 (-5415 1755);
PAINT MONO (-5415 1755);
FORCEPROP 1 LASTPIN (-5425 1575) $PN 2
J 0
(-5415 1555);
DISPLAY 0.787234 (-5415 1555);
PAINT MONO (-5415 1555);
FORCEPROP 1 LAST VOLTAGE 25V
J 0
(-5375 1675);
DISPLAY 0.787234 (-5375 1675);
FORCEPROP 0 LAST ROOM USB3_HUB2
J 0
(-5375 1825);
DISPLAY 0.680851 (-5375 1825);
PAINT RED (-5375 1825);
FORCEPROP 1 LAST TOLERANCE 10%
J 0
(-5375 1625);
DISPLAY 0.787234 (-5375 1625);
FORCEPROP 1 LAST VALUE 1UF
J 0
(-5375 1725);
DISPLAY 0.787234 (-5375 1725);
FORCEPROP 1 LAST MATERIAL X6S
J 0
(-5375 1575);
DISPLAY 0.787234 (-5375 1575);
FORCEPROP 1 LAST PACK_TYPE C0402
J 0
(-5375 1475);
DISPLAY 0.787234 (-5375 1475);
FORCEPROP 2 LAST CDS_LIB pure_quanta
J 0
(-5425 1675);
DISPLAY INVISIBLE (-5425 1675);
FORCEPROP 1 LAST PATH I21
J 0
(-5375 1825);
DISPLAY 0.978723 (-5375 1825);
PAINT WHITE (-5375 1825);
DISPLAY INVISIBLE (-5375 1825);
FORCEPROP 1 LAST PART_NUMBER CH5104KEB02
J 0
(-5375 1525);
DISPLAY 0.638298 (-5375 1525);
DISPLAY INVISIBLE (-5375 1525);
FORCEADD Q_CAP..1
(-4600 1675);
FORCEPROP 1 LAST LOCATION C6094
J 0
(-4550 1775);
DISPLAY 0.638298 (-4550 1775);
FORCEPROP 0 LAST $SEC 1
J 0
(-4550 1825);
DISPLAY 0.680851 (-4550 1825);
PAINT MONO (-4550 1825);
DISPLAY INVISIBLE (-4550 1825);
FORCEPROP 0 LAST CDS_SEC 1
J 0
(-4550 1825);
DISPLAY 0.680851 (-4550 1825);
DISPLAY INVISIBLE (-4550 1825);
FORCEPROP 1 LASTPIN (-4600 1775) $PN 1
J 0
(-4590 1755);
DISPLAY 0.787234 (-4590 1755);
PAINT MONO (-4590 1755);
FORCEPROP 1 LASTPIN (-4600 1575) $PN 2
J 0
(-4590 1555);
DISPLAY 0.787234 (-4590 1555);
PAINT MONO (-4590 1555);
FORCEPROP 1 LAST VALUE 0.01UF
J 0
(-4550 1725);
DISPLAY 0.510638 (-4550 1725);
FORCEPROP 0 LAST ROOM USB3_HUB2
J 0
(-4550 1825);
DISPLAY 0.361702 (-4550 1825);
PAINT RED (-4550 1825);
FORCEPROP 1 LAST VOLTAGE 50V
J 0
(-4550 1675);
DISPLAY 0.510638 (-4550 1675);
FORCEPROP 1 LAST TOLERANCE 10%
J 0
(-4550 1625);
DISPLAY 0.510638 (-4550 1625);
FORCEPROP 1 LAST MATERIAL X7R
J 0
(-4550 1575);
DISPLAY 0.510638 (-4550 1575);
FORCEPROP 1 LAST PACK_TYPE C0402
J 0
(-4550 1475);
DISPLAY 0.510638 (-4550 1475);
FORCEPROP 2 LAST CDS_LIB pure_quanta
J 0
(-4600 1675);
DISPLAY INVISIBLE (-4600 1675);
FORCEPROP 1 LAST PATH I22
J 0
(-4550 1825);
DISPLAY 0.978723 (-4550 1825);
PAINT WHITE (-4550 1825);
DISPLAY INVISIBLE (-4550 1825);
FORCEPROP 1 LAST PART_NUMBER CH31006KB18
J 0
(-4550 1525);
DISPLAY 0.638298 (-4550 1525);
DISPLAY INVISIBLE (-4550 1525);
FORCEADD Q_CAP..1
(-4350 1675);
FORCEPROP 1 LAST LOCATION C6095
J 0
(-4300 1775);
DISPLAY 0.638298 (-4300 1775);
FORCEPROP 0 LAST $SEC 1
J 0
(-4300 1825);
DISPLAY 0.680851 (-4300 1825);
PAINT MONO (-4300 1825);
DISPLAY INVISIBLE (-4300 1825);
FORCEPROP 0 LAST CDS_SEC 1
J 0
(-4300 1825);
DISPLAY 0.680851 (-4300 1825);
DISPLAY INVISIBLE (-4300 1825);
FORCEPROP 1 LASTPIN (-4350 1775) $PN 1
J 0
(-4340 1755);
DISPLAY 0.787234 (-4340 1755);
PAINT MONO (-4340 1755);
FORCEPROP 1 LASTPIN (-4350 1575) $PN 2
J 0
(-4340 1555);
DISPLAY 0.787234 (-4340 1555);
PAINT MONO (-4340 1555);
FORCEPROP 1 LAST VALUE 0.1UF
J 0
(-4300 1725);
DISPLAY 0.638298 (-4300 1725);
FORCEPROP 0 LAST ROOM USB3_HUB2
J 0
(-4300 1825);
DISPLAY 0.446809 (-4300 1825);
PAINT RED (-4300 1825);
FORCEPROP 1 LAST PACK_TYPE 0402
J 0
(-4300 1475);
DISPLAY 0.638298 (-4300 1475);
FORCEPROP 1 LAST MATERIAL X7R
J 0
(-4300 1575);
DISPLAY 0.638298 (-4300 1575);
FORCEPROP 1 LAST VOLTAGE 25V
J 0
(-4300 1675);
DISPLAY 0.638298 (-4300 1675);
FORCEPROP 1 LAST TOLERANCE 10%
J 0
(-4300 1625);
DISPLAY 0.638298 (-4300 1625);
FORCEPROP 2 LAST CDS_LIB pure_quanta
J 0
(-4350 1675);
DISPLAY INVISIBLE (-4350 1675);
FORCEPROP 1 LAST PATH I23
J 0
(-4300 1825);
DISPLAY 0.978723 (-4300 1825);
PAINT WHITE (-4300 1825);
DISPLAY INVISIBLE (-4300 1825);
FORCEPROP 1 LAST PART_NUMBER CH4104K1B00
J 0
(-4300 1525);
DISPLAY 0.808511 (-4300 1525);
DISPLAY INVISIBLE (-4300 1525);
FORCEADD Q_CAP..1
(-5025 1675);
FORCEPROP 1 LAST LOCATION C6093
J 0
(-4975 1775);
DISPLAY 0.638298 (-4975 1775);
FORCEPROP 0 LAST $SEC 1
J 0
(-4975 1825);
DISPLAY 0.680851 (-4975 1825);
PAINT MONO (-4975 1825);
DISPLAY INVISIBLE (-4975 1825);
FORCEPROP 0 LAST CDS_SEC 1
J 0
(-4975 1825);
DISPLAY 0.680851 (-4975 1825);
DISPLAY INVISIBLE (-4975 1825);
FORCEPROP 1 LASTPIN (-5025 1775) $PN 1
J 0
(-5015 1755);
DISPLAY 0.787234 (-5015 1755);
PAINT MONO (-5015 1755);
FORCEPROP 1 LASTPIN (-5025 1575) $PN 2
J 0
(-5015 1555);
DISPLAY 0.787234 (-5015 1555);
PAINT MONO (-5015 1555);
FORCEPROP 1 LAST VOLTAGE 50V
J 0
(-4975 1675);
DISPLAY 0.638298 (-4975 1675);
FORCEPROP 1 LAST MATERIAL COG
J 0
(-4975 1575);
DISPLAY 0.638298 (-4975 1575);
FORCEPROP 1 LAST TOLERANCE 0.05P
J 0
(-4975 1625);
DISPLAY 0.638298 (-4975 1625);
FORCEPROP 1 LAST VALUE 1PF
J 0
(-4975 1725);
DISPLAY 0.638298 (-4975 1725);
FORCEPROP 1 LAST PACK_TYPE C0402
J 0
(-4975 1475);
DISPLAY 0.638298 (-4975 1475);
FORCEPROP 0 LAST ROOM USB3_HUB2
J 0
(-4975 1825);
DISPLAY 0.553191 (-4975 1825);
PAINT RED (-4975 1825);
FORCEPROP 2 LAST CDS_LIB pure_quanta
J 0
(-5025 1675);
DISPLAY INVISIBLE (-5025 1675);
FORCEPROP 1 LAST PATH I24
J 0
(-4975 1825);
DISPLAY 0.978723 (-4975 1825);
PAINT WHITE (-4975 1825);
DISPLAY INVISIBLE (-4975 1825);
FORCEPROP 1 LAST PART_NUMBER CH-106T0B00
J 0
(-4975 1525);
DISPLAY 0.638298 (-4975 1525);
DISPLAY INVISIBLE (-4975 1525);
FORCEADD Q_CAP..1
(-3575 1675);
FORCEPROP 1 LAST LOCATION C6098
J 0
(-3525 1775);
DISPLAY 0.638298 (-3525 1775);
FORCEPROP 0 LAST $SEC 1
J 0
(-3525 1825);
DISPLAY 0.680851 (-3525 1825);
PAINT MONO (-3525 1825);
DISPLAY INVISIBLE (-3525 1825);
FORCEPROP 0 LAST CDS_SEC 1
J 0
(-3525 1825);
DISPLAY 0.680851 (-3525 1825);
DISPLAY INVISIBLE (-3525 1825);
FORCEPROP 1 LASTPIN (-3575 1775) $PN 1
J 0
(-3565 1755);
DISPLAY 0.787234 (-3565 1755);
PAINT MONO (-3565 1755);
FORCEPROP 1 LASTPIN (-3575 1575) $PN 2
J 0
(-3565 1555);
DISPLAY 0.787234 (-3565 1555);
PAINT MONO (-3565 1555);
FORCEPROP 0 LAST ROOM USB3_HUB2
J 0
(-3525 1825);
DISPLAY 0.446809 (-3525 1825);
PAINT RED (-3525 1825);
FORCEPROP 1 LAST VOLTAGE 25V
J 0
(-3525 1675);
DISPLAY 0.638298 (-3525 1675);
FORCEPROP 1 LAST VALUE 0.1UF
J 0
(-3525 1725);
DISPLAY 0.638298 (-3525 1725);
FORCEPROP 1 LAST MATERIAL X7R
J 0
(-3525 1575);
DISPLAY 0.638298 (-3525 1575);
FORCEPROP 1 LAST TOLERANCE 10%
J 0
(-3525 1625);
DISPLAY 0.638298 (-3525 1625);
FORCEPROP 1 LAST PACK_TYPE 0402
J 0
(-3525 1475);
DISPLAY 0.638298 (-3525 1475);
FORCEPROP 2 LAST CDS_LIB pure_quanta
J 0
(-3575 1675);
DISPLAY INVISIBLE (-3575 1675);
FORCEPROP 1 LAST PATH I25
J 0
(-3525 1825);
DISPLAY 0.978723 (-3525 1825);
PAINT WHITE (-3525 1825);
DISPLAY INVISIBLE (-3525 1825);
FORCEPROP 1 LAST PART_NUMBER CH4104K1B00
J 0
(-3525 1525);
DISPLAY 0.808511 (-3525 1525);
DISPLAY INVISIBLE (-3525 1525);
FORCEADD Q_CAP..1
(-3825 1675);
FORCEPROP 1 LAST LOCATION C6097
J 0
(-3775 1775);
DISPLAY 0.638298 (-3775 1775);
FORCEPROP 0 LAST $SEC 1
J 0
(-3775 1825);
DISPLAY 0.680851 (-3775 1825);
PAINT MONO (-3775 1825);
DISPLAY INVISIBLE (-3775 1825);
FORCEPROP 0 LAST CDS_SEC 1
J 0
(-3775 1825);
DISPLAY 0.680851 (-3775 1825);
DISPLAY INVISIBLE (-3775 1825);
FORCEPROP 1 LASTPIN (-3825 1775) $PN 1
J 0
(-3815 1755);
DISPLAY 0.787234 (-3815 1755);
PAINT MONO (-3815 1755);
FORCEPROP 1 LASTPIN (-3825 1575) $PN 2
J 0
(-3815 1555);
DISPLAY 0.787234 (-3815 1555);
PAINT MONO (-3815 1555);
FORCEPROP 0 LAST ROOM USB3_HUB2
J 0
(-3775 1825);
DISPLAY 0.446809 (-3775 1825);
PAINT RED (-3775 1825);
FORCEPROP 1 LAST TOLERANCE 10%
J 0
(-3775 1625);
DISPLAY 0.510638 (-3775 1625);
FORCEPROP 1 LAST VOLTAGE 50V
J 0
(-3775 1675);
DISPLAY 0.510638 (-3775 1675);
FORCEPROP 1 LAST VALUE 0.01UF
J 0
(-3775 1725);
DISPLAY 0.510638 (-3775 1725);
FORCEPROP 1 LAST MATERIAL X7R
J 0
(-3775 1575);
DISPLAY 0.510638 (-3775 1575);
FORCEPROP 1 LAST PACK_TYPE C0402
J 0
(-3775 1475);
DISPLAY 0.510638 (-3775 1475);
FORCEPROP 2 LAST CDS_LIB pure_quanta
J 0
(-3825 1675);
DISPLAY INVISIBLE (-3825 1675);
FORCEPROP 1 LAST PATH I26
J 0
(-3775 1825);
DISPLAY 0.978723 (-3775 1825);
PAINT WHITE (-3775 1825);
DISPLAY INVISIBLE (-3775 1825);
FORCEPROP 1 LAST PART_NUMBER CH31006KB18
J 0
(-3775 1525);
DISPLAY 0.638298 (-3775 1525);
DISPLAY INVISIBLE (-3775 1525);
FORCEADD Q_CAP..1
(-4075 1675);
FORCEPROP 1 LAST LOCATION C6096
J 0
(-4025 1775);
DISPLAY 0.787234 (-4025 1775);
FORCEPROP 0 LAST $SEC 1
J 0
(-4025 1825);
DISPLAY 0.680851 (-4025 1825);
PAINT MONO (-4025 1825);
DISPLAY INVISIBLE (-4025 1825);
FORCEPROP 0 LAST CDS_SEC 1
J 0
(-4025 1825);
DISPLAY 0.680851 (-4025 1825);
DISPLAY INVISIBLE (-4025 1825);
FORCEPROP 1 LASTPIN (-4075 1775) $PN 1
J 0
(-4065 1755);
DISPLAY 0.787234 (-4065 1755);
PAINT MONO (-4065 1755);
FORCEPROP 1 LASTPIN (-4075 1575) $PN 2
J 0
(-4065 1555);
DISPLAY 0.787234 (-4065 1555);
PAINT MONO (-4065 1555);
FORCEPROP 0 LAST ROOM USB3_HUB2
J 0
(-4025 1825);
DISPLAY 0.446809 (-4025 1825);
PAINT RED (-4025 1825);
FORCEPROP 1 LAST VALUE 1PF
J 0
(-4025 1725);
DISPLAY 0.638298 (-4025 1725);
FORCEPROP 1 LAST TOLERANCE 0.05P
J 0
(-4025 1625);
DISPLAY 0.638298 (-4025 1625);
FORCEPROP 1 LAST VOLTAGE 50V
J 0
(-4025 1675);
DISPLAY 0.638298 (-4025 1675);
FORCEPROP 1 LAST MATERIAL COG
J 0
(-4025 1575);
DISPLAY 0.638298 (-4025 1575);
FORCEPROP 1 LAST PACK_TYPE C0402
J 0
(-4025 1475);
DISPLAY 0.638298 (-4025 1475);
FORCEPROP 2 LAST CDS_LIB pure_quanta
J 0
(-4075 1675);
DISPLAY INVISIBLE (-4075 1675);
FORCEPROP 1 LAST PATH I27
J 0
(-4025 1825);
DISPLAY 0.978723 (-4025 1825);
PAINT WHITE (-4025 1825);
DISPLAY INVISIBLE (-4025 1825);
FORCEPROP 1 LAST PART_NUMBER CH-106T0B00
J 0
(-4025 1525);
DISPLAY 0.638298 (-4025 1525);
DISPLAY INVISIBLE (-4025 1525);
FORCEADD Q_CAP..1
(-2825 1675);
FORCEPROP 1 LAST LOCATION C6101
J 0
(-2775 1775);
DISPLAY 0.638298 (-2775 1775);
FORCEPROP 0 LAST $SEC 1
J 0
(-2775 1825);
DISPLAY 0.680851 (-2775 1825);
PAINT MONO (-2775 1825);
DISPLAY INVISIBLE (-2775 1825);
FORCEPROP 0 LAST CDS_SEC 1
J 0
(-2775 1825);
DISPLAY 0.680851 (-2775 1825);
DISPLAY INVISIBLE (-2775 1825);
FORCEPROP 1 LASTPIN (-2825 1775) $PN 1
J 0
(-2815 1755);
DISPLAY 0.787234 (-2815 1755);
PAINT MONO (-2815 1755);
FORCEPROP 1 LASTPIN (-2825 1575) $PN 2
J 0
(-2815 1555);
DISPLAY 0.787234 (-2815 1555);
PAINT MONO (-2815 1555);
FORCEPROP 1 LAST TOLERANCE 10%
J 0
(-2775 1625);
DISPLAY 0.638298 (-2775 1625);
FORCEPROP 0 LAST ROOM USB3_HUB2
J 0
(-2775 1825);
DISPLAY 0.446809 (-2775 1825);
PAINT RED (-2775 1825);
FORCEPROP 1 LAST VOLTAGE 25V
J 0
(-2775 1675);
DISPLAY 0.638298 (-2775 1675);
FORCEPROP 1 LAST VALUE 0.1UF
J 0
(-2775 1725);
DISPLAY 0.638298 (-2775 1725);
FORCEPROP 1 LAST MATERIAL X7R
J 0
(-2775 1575);
DISPLAY 0.638298 (-2775 1575);
FORCEPROP 1 LAST PACK_TYPE 0402
J 0
(-2775 1475);
DISPLAY 0.638298 (-2775 1475);
FORCEPROP 2 LAST CDS_LIB pure_quanta
J 0
(-2825 1675);
DISPLAY INVISIBLE (-2825 1675);
FORCEPROP 1 LAST PATH I28
J 0
(-2775 1825);
DISPLAY 0.978723 (-2775 1825);
PAINT WHITE (-2775 1825);
DISPLAY INVISIBLE (-2775 1825);
FORCEPROP 1 LAST PART_NUMBER CH4104K1B00
J 0
(-2775 1525);
DISPLAY 0.808511 (-2775 1525);
DISPLAY INVISIBLE (-2775 1525);
FORCEADD Q_CAP..1
(-3075 1675);
FORCEPROP 1 LAST LOCATION C6100
J 0
(-3025 1775);
DISPLAY 0.638298 (-3025 1775);
FORCEPROP 0 LAST $SEC 1
J 0
(-3025 1825);
DISPLAY 0.680851 (-3025 1825);
PAINT MONO (-3025 1825);
DISPLAY INVISIBLE (-3025 1825);
FORCEPROP 0 LAST CDS_SEC 1
J 0
(-3025 1825);
DISPLAY 0.680851 (-3025 1825);
DISPLAY INVISIBLE (-3025 1825);
FORCEPROP 1 LASTPIN (-3075 1775) $PN 1
J 0
(-3065 1755);
DISPLAY 0.787234 (-3065 1755);
PAINT MONO (-3065 1755);
FORCEPROP 1 LASTPIN (-3075 1575) $PN 2
J 0
(-3065 1555);
DISPLAY 0.787234 (-3065 1555);
PAINT MONO (-3065 1555);
FORCEPROP 1 LAST VALUE 0.01UF
J 0
(-3025 1725);
DISPLAY 0.510638 (-3025 1725);
FORCEPROP 1 LAST VOLTAGE 50V
J 0
(-3025 1675);
DISPLAY 0.510638 (-3025 1675);
FORCEPROP 1 LAST TOLERANCE 10%
J 0
(-3025 1625);
DISPLAY 0.510638 (-3025 1625);
FORCEPROP 0 LAST ROOM USB3_HUB2
J 0
(-3025 1825);
DISPLAY 0.446809 (-3025 1825);
PAINT RED (-3025 1825);
FORCEPROP 1 LAST MATERIAL X7R
J 0
(-3025 1575);
DISPLAY 0.510638 (-3025 1575);
FORCEPROP 1 LAST PACK_TYPE C0402
J 0
(-3025 1475);
DISPLAY 0.510638 (-3025 1475);
FORCEPROP 2 LAST CDS_LIB pure_quanta
J 0
(-3075 1675);
DISPLAY INVISIBLE (-3075 1675);
FORCEPROP 1 LAST PATH I29
J 0
(-3025 1825);
DISPLAY 0.978723 (-3025 1825);
PAINT WHITE (-3025 1825);
DISPLAY INVISIBLE (-3025 1825);
FORCEPROP 1 LAST PART_NUMBER CH31006KB18
J 0
(-3025 1525);
DISPLAY 0.638298 (-3025 1525);
DISPLAY INVISIBLE (-3025 1525);
FORCEADD Q_CAP..1
(-3325 1675);
FORCEPROP 1 LAST LOCATION C6099
J 0
(-3275 1775);
DISPLAY 0.978723 (-3275 1775);
FORCEPROP 0 LAST $SEC 1
J 0
(-3275 1825);
DISPLAY 0.680851 (-3275 1825);
PAINT MONO (-3275 1825);
DISPLAY INVISIBLE (-3275 1825);
FORCEPROP 0 LAST CDS_SEC 1
J 0
(-3275 1825);
DISPLAY 0.680851 (-3275 1825);
DISPLAY INVISIBLE (-3275 1825);
FORCEPROP 1 LASTPIN (-3325 1775) $PN 1
J 0
(-3315 1755);
DISPLAY 0.787234 (-3315 1755);
PAINT MONO (-3315 1755);
FORCEPROP 1 LASTPIN (-3325 1575) $PN 2
J 0
(-3315 1555);
DISPLAY 0.787234 (-3315 1555);
PAINT MONO (-3315 1555);
FORCEPROP 0 LAST ROOM USB3_HUB2
J 0
(-3275 1825);
DISPLAY 0.446809 (-3275 1825);
PAINT RED (-3275 1825);
FORCEPROP 1 LAST VALUE 1PF
J 0
(-3275 1725);
DISPLAY 0.638298 (-3275 1725);
FORCEPROP 1 LAST VOLTAGE 50V
J 0
(-3275 1675);
DISPLAY 0.638298 (-3275 1675);
FORCEPROP 1 LAST MATERIAL COG
J 0
(-3275 1575);
DISPLAY 0.638298 (-3275 1575);
FORCEPROP 1 LAST TOLERANCE 0.05P
J 0
(-3275 1625);
DISPLAY 0.638298 (-3275 1625);
FORCEPROP 1 LAST PACK_TYPE C0402
J 0
(-3275 1475);
DISPLAY 0.638298 (-3275 1475);
FORCEPROP 2 LAST CDS_LIB pure_quanta
J 0
(-3325 1675);
DISPLAY INVISIBLE (-3325 1675);
FORCEPROP 1 LAST PATH I30
J 0
(-3275 1825);
DISPLAY 0.978723 (-3275 1825);
PAINT WHITE (-3275 1825);
DISPLAY INVISIBLE (-3275 1825);
FORCEPROP 1 LAST PART_NUMBER CH-106T0B00
J 0
(-3275 1525);
DISPLAY 0.638298 (-3275 1525);
DISPLAY INVISIBLE (-3275 1525);
FORCEADD Q_CAP..1
(-2050 1675);
FORCEPROP 1 LAST LOCATION C6104
J 0
(-2000 1775);
DISPLAY 0.638298 (-2000 1775);
FORCEPROP 0 LAST $SEC 1
J 0
(-2000 1825);
DISPLAY 0.680851 (-2000 1825);
PAINT MONO (-2000 1825);
DISPLAY INVISIBLE (-2000 1825);
FORCEPROP 0 LAST CDS_SEC 1
J 0
(-2000 1825);
DISPLAY 0.680851 (-2000 1825);
DISPLAY INVISIBLE (-2000 1825);
FORCEPROP 1 LASTPIN (-2050 1775) $PN 1
J 0
(-2040 1755);
DISPLAY 0.787234 (-2040 1755);
PAINT MONO (-2040 1755);
FORCEPROP 1 LASTPIN (-2050 1575) $PN 2
J 0
(-2040 1555);
DISPLAY 0.787234 (-2040 1555);
PAINT MONO (-2040 1555);
FORCEPROP 0 LAST ROOM USB3_HUB2
J 0
(-2000 1825);
DISPLAY 0.553191 (-2000 1825);
PAINT RED (-2000 1825);
FORCEPROP 1 LAST VOLTAGE 25V
J 0
(-2000 1675);
DISPLAY 0.638298 (-2000 1675);
FORCEPROP 1 LAST VALUE 0.1UF
J 0
(-2000 1725);
DISPLAY 0.638298 (-2000 1725);
FORCEPROP 1 LAST TOLERANCE 10%
J 0
(-2000 1625);
DISPLAY 0.638298 (-2000 1625);
FORCEPROP 1 LAST MATERIAL X7R
J 0
(-2000 1575);
DISPLAY 0.638298 (-2000 1575);
FORCEPROP 1 LAST PACK_TYPE 0402
J 0
(-2000 1475);
DISPLAY 0.638298 (-2000 1475);
FORCEPROP 2 LAST CDS_LIB pure_quanta
J 0
(-2050 1675);
DISPLAY INVISIBLE (-2050 1675);
FORCEPROP 1 LAST PATH I31
J 0
(-2000 1825);
DISPLAY 0.978723 (-2000 1825);
PAINT WHITE (-2000 1825);
DISPLAY INVISIBLE (-2000 1825);
FORCEPROP 1 LAST PART_NUMBER CH4104K1B00
J 0
(-2000 1525);
DISPLAY 0.808511 (-2000 1525);
DISPLAY INVISIBLE (-2000 1525);
FORCEADD Q_CAP..1
(-2325 1675);
FORCEPROP 1 LAST LOCATION C6103
J 0
(-2275 1775);
DISPLAY 0.638298 (-2275 1775);
FORCEPROP 0 LAST $SEC 1
J 0
(-2275 1825);
DISPLAY 0.680851 (-2275 1825);
PAINT MONO (-2275 1825);
DISPLAY INVISIBLE (-2275 1825);
FORCEPROP 0 LAST CDS_SEC 1
J 0
(-2275 1825);
DISPLAY 0.680851 (-2275 1825);
DISPLAY INVISIBLE (-2275 1825);
FORCEPROP 1 LASTPIN (-2325 1775) $PN 1
J 0
(-2315 1755);
DISPLAY 0.787234 (-2315 1755);
PAINT MONO (-2315 1755);
FORCEPROP 1 LASTPIN (-2325 1575) $PN 2
J 0
(-2315 1555);
DISPLAY 0.787234 (-2315 1555);
PAINT MONO (-2315 1555);
FORCEPROP 0 LAST ROOM USB3_HUB2
J 0
(-2275 1825);
DISPLAY 0.446809 (-2275 1825);
PAINT RED (-2275 1825);
FORCEPROP 1 LAST VALUE 0.01UF
J 0
(-2275 1725);
DISPLAY 0.510638 (-2275 1725);
FORCEPROP 1 LAST TOLERANCE 10%
J 0
(-2275 1625);
DISPLAY 0.510638 (-2275 1625);
FORCEPROP 1 LAST VOLTAGE 50V
J 0
(-2275 1675);
DISPLAY 0.510638 (-2275 1675);
FORCEPROP 1 LAST PACK_TYPE C0402
J 0
(-2275 1475);
DISPLAY 0.510638 (-2275 1475);
FORCEPROP 1 LAST MATERIAL X7R
J 0
(-2275 1575);
DISPLAY 0.510638 (-2275 1575);
FORCEPROP 2 LAST CDS_LIB pure_quanta
J 0
(-2325 1675);
DISPLAY INVISIBLE (-2325 1675);
FORCEPROP 1 LAST PATH I32
J 0
(-2275 1825);
DISPLAY 0.978723 (-2275 1825);
PAINT WHITE (-2275 1825);
DISPLAY INVISIBLE (-2275 1825);
FORCEPROP 1 LAST PART_NUMBER CH31006KB18
J 0
(-2275 1525);
DISPLAY 0.638298 (-2275 1525);
DISPLAY INVISIBLE (-2275 1525);
FORCEADD Q_CAP..1
(-2575 1675);
FORCEPROP 1 LAST LOCATION C6102
J 0
(-2525 1775);
DISPLAY 0.978723 (-2525 1775);
FORCEPROP 0 LAST $SEC 1
J 0
(-2525 1825);
DISPLAY 0.680851 (-2525 1825);
PAINT MONO (-2525 1825);
DISPLAY INVISIBLE (-2525 1825);
FORCEPROP 0 LAST CDS_SEC 1
J 0
(-2525 1825);
DISPLAY 0.680851 (-2525 1825);
DISPLAY INVISIBLE (-2525 1825);
FORCEPROP 1 LASTPIN (-2575 1775) $PN 1
J 0
(-2565 1755);
DISPLAY 0.787234 (-2565 1755);
PAINT MONO (-2565 1755);
FORCEPROP 1 LASTPIN (-2575 1575) $PN 2
J 0
(-2565 1555);
DISPLAY 0.787234 (-2565 1555);
PAINT MONO (-2565 1555);
FORCEPROP 1 LAST VOLTAGE 50V
J 0
(-2525 1675);
DISPLAY 0.638298 (-2525 1675);
FORCEPROP 0 LAST ROOM USB3_HUB2
J 0
(-2525 1825);
DISPLAY 0.446809 (-2525 1825);
PAINT RED (-2525 1825);
FORCEPROP 1 LAST VALUE 1PF
J 0
(-2525 1725);
DISPLAY 0.638298 (-2525 1725);
FORCEPROP 1 LAST TOLERANCE 0.05P
J 0
(-2525 1625);
DISPLAY 0.638298 (-2525 1625);
FORCEPROP 1 LAST MATERIAL COG
J 0
(-2525 1575);
DISPLAY 0.638298 (-2525 1575);
FORCEPROP 1 LAST PACK_TYPE C0402
J 0
(-2525 1475);
DISPLAY 0.638298 (-2525 1475);
FORCEPROP 2 LAST CDS_LIB pure_quanta
J 0
(-2575 1675);
DISPLAY INVISIBLE (-2575 1675);
FORCEPROP 1 LAST PATH I33
J 0
(-2525 1825);
DISPLAY 0.978723 (-2525 1825);
PAINT WHITE (-2525 1825);
DISPLAY INVISIBLE (-2525 1825);
FORCEPROP 1 LAST PART_NUMBER CH-106T0B00
J 0
(-2525 1525);
DISPLAY 0.638298 (-2525 1525);
DISPLAY INVISIBLE (-2525 1525);
FORCEADD GND..1
(-5425 1300);
FORCEPROP 3 LASTPIN (-5425 1350) SIG_NAME GND\g
J 0
(-5415 1360);
DISPLAY 0.659574 (-5415 1360);
PAINT MONO (-5415 1360);
DISPLAY INVISIBLE (-5415 1360);
FORCEPROP 1 LAST SIZE 1B
J 0
(-5350 1250);
DISPLAY 1.170213 (-5350 1250);
PAINT AQUA (-5350 1250);
DISPLAY INVISIBLE (-5350 1250);
FORCEPROP 2 LAST CDS_LIB pure_quanta_power
J 0
(-5425 1300);
DISPLAY INVISIBLE (-5425 1300);
FORCEPROP 1 LAST HDL_POWER GND
J 0
(-5425 1450);
DISPLAY 1.170213 (-5425 1450);
PAINT GREEN (-5425 1450);
DISPLAY INVISIBLE (-5425 1450);
FORCEPROP 1 LAST PATH I34
J 0
(-5350 1300);
DISPLAY 0.872340 (-5350 1300);
PAINT AQUA (-5350 1300);
DISPLAY INVISIBLE (-5350 1300);
FORCEADD UNIVERSAL_POWER..1
(-8300 1275);
FORCEPROP 3 LASTPIN (-8300 1225) SIG_NAME P1V2_AUX\g
J 0
(-8290 1235);
DISPLAY 0.659574 (-8290 1235);
PAINT MONO (-8290 1235);
DISPLAY INVISIBLE (-8290 1235);
FORCEPROP 1 LAST HDL_POWER P1V2_AUX
J 1
(-8300 1325);
DISPLAY 0.489362 (-8300 1325);
PAINT GREEN (-8300 1325);
FORCEPROP 2 LAST BOM_COST VR_SYSTEM
J 0
(-8300 1375);
DISPLAY 0.617021 (-8300 1375);
PAINT PURPLE (-8300 1375);
DISPLAY INVISIBLE (-8300 1375);
FORCEPROP 2 LAST CDS_LIB pure_quanta_power
J 0
(-8300 1275);
DISPLAY INVISIBLE (-8300 1275);
FORCEPROP 1 LAST PATH I35
J 0
(-8250 1300);
DISPLAY 0.872340 (-8250 1300);
PAINT AQUA (-8250 1300);
DISPLAY INVISIBLE (-8250 1300);
FORCEADD Q_CAP..1
(-7100 825);
FORCEPROP 1 LAST LOCATION C6105
J 0
(-7050 925);
DISPLAY 0.765957 (-7050 925);
PAINT SKYBLUE (-7050 925);
FORCEPROP 0 LAST $SEC 1
J 0
(-7050 975);
DISPLAY 0.680851 (-7050 975);
PAINT MONO (-7050 975);
DISPLAY INVISIBLE (-7050 975);
FORCEPROP 0 LAST CDS_SEC 1
J 0
(-7050 975);
DISPLAY 0.680851 (-7050 975);
DISPLAY INVISIBLE (-7050 975);
FORCEPROP 1 LASTPIN (-7100 925) $PN 1
J 0
(-7090 905);
DISPLAY 0.787234 (-7090 905);
PAINT MONO (-7090 905);
FORCEPROP 1 LASTPIN (-7100 725) $PN 2
J 0
(-7090 705);
DISPLAY 0.787234 (-7090 705);
PAINT MONO (-7090 705);
FORCEPROP 1 LAST MATERIAL X6S
J 0
(-7050 725);
DISPLAY 0.617021 (-7050 725);
PAINT SKYBLUE (-7050 725);
FORCEPROP 1 LAST TOLERANCE 10%
J 0
(-7050 775);
DISPLAY 0.617021 (-7050 775);
PAINT SKYBLUE (-7050 775);
FORCEPROP 1 LAST PACK_TYPE C0805
J 0
(-7050 625);
DISPLAY 0.617021 (-7050 625);
PAINT SKYBLUE (-7050 625);
FORCEPROP 0 LAST ROOM USB3_HUB2
J 0
(-7050 1025);
DISPLAY 0.553191 (-7050 1025);
PAINT RED (-7050 1025);
FORCEPROP 1 LAST VOLTAGE 25V
J 0
(-7050 825);
DISPLAY 0.617021 (-7050 825);
PAINT SKYBLUE (-7050 825);
FORCEPROP 1 LAST VALUE 10UF
J 0
(-7050 875);
DISPLAY 0.617021 (-7050 875);
PAINT SKYBLUE (-7050 875);
FORCEPROP 2 LAST CDS_LIB pure_quanta
J 0
(-7100 825);
DISPLAY INVISIBLE (-7100 825);
FORCEPROP 1 LAST PATH I36
J 0
(-7050 975);
DISPLAY 0.978723 (-7050 975);
PAINT WHITE (-7050 975);
DISPLAY INVISIBLE (-7050 975);
FORCEPROP 1 LAST PART_NUMBER CH6104KEA00
J 0
(-7050 675);
DISPLAY 0.617021 (-7050 675);
PAINT SKYBLUE (-7050 675);
DISPLAY INVISIBLE (-7050 675);
FORCEADD UNIVERSAL_POWER..1
(-7100 1275);
FORCEPROP 3 LASTPIN (-7100 1225) SIG_NAME P1V2_CPU0_USB2_DVDD12\g
J 0
(-7090 1235);
DISPLAY 0.659574 (-7090 1235);
PAINT MONO (-7090 1235);
DISPLAY INVISIBLE (-7090 1235);
FORCEPROP 1 LAST HDL_POWER P1V2_CPU0_USB2_DVDD12
J 1
(-7100 1325);
DISPLAY 0.489362 (-7100 1325);
PAINT GREEN (-7100 1325);
FORCEPROP 2 LAST CDS_LIB pure_quanta_power
J 0
(-7100 1275);
DISPLAY INVISIBLE (-7100 1275);
FORCEPROP 2 LAST BOM_COST VR_SYSTEM
J 0
(-7100 1375);
DISPLAY 0.617021 (-7100 1375);
PAINT PURPLE (-7100 1375);
DISPLAY INVISIBLE (-7100 1375);
FORCEPROP 1 LAST PATH I37
J 0
(-7050 1300);
DISPLAY 0.872340 (-7050 1300);
PAINT AQUA (-7050 1300);
DISPLAY INVISIBLE (-7050 1300);
FORCEADD GND..1
(-7100 400);
FORCEPROP 3 LASTPIN (-7100 450) SIG_NAME GND\g
J 0
(-7090 460);
DISPLAY 0.659574 (-7090 460);
PAINT MONO (-7090 460);
DISPLAY INVISIBLE (-7090 460);
FORCEPROP 2 LAST CDS_LIB pure_quanta_power
J 0
(-7100 400);
DISPLAY INVISIBLE (-7100 400);
FORCEPROP 1 LAST SIZE 1B
J 0
(-7025 350);
DISPLAY 1.170213 (-7025 350);
PAINT AQUA (-7025 350);
DISPLAY INVISIBLE (-7025 350);
FORCEPROP 1 LAST HDL_POWER GND
J 0
(-7100 550);
DISPLAY 1.170213 (-7100 550);
PAINT GREEN (-7100 550);
DISPLAY INVISIBLE (-7100 550);
FORCEPROP 1 LAST PATH I38
J 0
(-7025 400);
DISPLAY 0.872340 (-7025 400);
PAINT AQUA (-7025 400);
DISPLAY INVISIBLE (-7025 400);
FORCEADD Q_CAP..1
(-6025 825);
FORCEPROP 1 LAST LOCATION C6108
J 0
(-5975 925);
DISPLAY 0.638298 (-5975 925);
FORCEPROP 0 LAST $SEC 1
J 0
(-5975 975);
DISPLAY 0.680851 (-5975 975);
PAINT MONO (-5975 975);
DISPLAY INVISIBLE (-5975 975);
FORCEPROP 0 LAST CDS_SEC 1
J 0
(-5975 975);
DISPLAY 0.680851 (-5975 975);
DISPLAY INVISIBLE (-5975 975);
FORCEPROP 1 LASTPIN (-6025 925) $PN 1
J 0
(-6015 905);
DISPLAY 0.787234 (-6015 905);
PAINT MONO (-6015 905);
FORCEPROP 1 LASTPIN (-6025 725) $PN 2
J 0
(-6015 705);
DISPLAY 0.787234 (-6015 705);
PAINT MONO (-6015 705);
FORCEPROP 1 LAST MATERIAL X7R
J 0
(-5975 725);
DISPLAY 0.638298 (-5975 725);
FORCEPROP 0 LAST ROOM USB3_HUB2
J 0
(-5975 1025);
DISPLAY 0.446809 (-5975 1025);
PAINT RED (-5975 1025);
FORCEPROP 1 LAST PACK_TYPE 0402
J 0
(-5975 625);
DISPLAY 0.638298 (-5975 625);
FORCEPROP 1 LAST VALUE 0.1UF
J 0
(-5975 875);
DISPLAY 0.638298 (-5975 875);
FORCEPROP 1 LAST VOLTAGE 25V
J 0
(-5975 825);
DISPLAY 0.638298 (-5975 825);
FORCEPROP 1 LAST TOLERANCE 10%
J 0
(-5975 775);
DISPLAY 0.638298 (-5975 775);
FORCEPROP 2 LAST CDS_LIB pure_quanta
J 0
(-6025 825);
DISPLAY INVISIBLE (-6025 825);
FORCEPROP 1 LAST PATH I39
J 0
(-5975 975);
DISPLAY 0.978723 (-5975 975);
PAINT WHITE (-5975 975);
DISPLAY INVISIBLE (-5975 975);
FORCEPROP 1 LAST PART_NUMBER CH4104K1B00
J 0
(-5975 675);
DISPLAY 0.808511 (-5975 675);
DISPLAY INVISIBLE (-5975 675);
FORCEADD Q_CAP..1
(-6275 825);
FORCEPROP 1 LAST LOCATION C6107
J 0
(-6225 925);
DISPLAY 0.638298 (-6225 925);
FORCEPROP 0 LAST $SEC 1
J 0
(-6225 975);
DISPLAY 0.680851 (-6225 975);
PAINT MONO (-6225 975);
DISPLAY INVISIBLE (-6225 975);
FORCEPROP 0 LAST CDS_SEC 1
J 0
(-6225 975);
DISPLAY 0.680851 (-6225 975);
DISPLAY INVISIBLE (-6225 975);
FORCEPROP 1 LASTPIN (-6275 925) $PN 1
J 0
(-6265 905);
DISPLAY 0.787234 (-6265 905);
PAINT MONO (-6265 905);
FORCEPROP 1 LASTPIN (-6275 725) $PN 2
J 0
(-6265 705);
DISPLAY 0.787234 (-6265 705);
PAINT MONO (-6265 705);
FORCEPROP 1 LAST MATERIAL X7R
J 0
(-6225 725);
DISPLAY 0.510638 (-6225 725);
FORCEPROP 1 LAST VOLTAGE 50V
J 0
(-6225 825);
DISPLAY 0.510638 (-6225 825);
FORCEPROP 0 LAST ROOM USB3_HUB2
J 0
(-6225 1025);
DISPLAY 0.446809 (-6225 1025);
PAINT RED (-6225 1025);
FORCEPROP 1 LAST VALUE 0.01UF
J 0
(-6225 875);
DISPLAY 0.510638 (-6225 875);
FORCEPROP 1 LAST PACK_TYPE C0402
J 0
(-6225 625);
DISPLAY 0.510638 (-6225 625);
FORCEPROP 1 LAST TOLERANCE 10%
J 0
(-6225 775);
DISPLAY 0.510638 (-6225 775);
FORCEPROP 2 LAST CDS_LIB pure_quanta
J 0
(-6275 825);
DISPLAY INVISIBLE (-6275 825);
FORCEPROP 1 LAST PATH I40
J 0
(-6225 975);
DISPLAY 0.978723 (-6225 975);
PAINT WHITE (-6225 975);
DISPLAY INVISIBLE (-6225 975);
FORCEPROP 1 LAST PART_NUMBER CH31006KB18
J 0
(-6225 675);
DISPLAY 0.638298 (-6225 675);
DISPLAY INVISIBLE (-6225 675);
FORCEADD Q_CAP..1
(-6700 825);
FORCEPROP 1 LAST LOCATION C6106
J 0
(-6650 925);
DISPLAY 0.638298 (-6650 925);
FORCEPROP 0 LAST $SEC 1
J 0
(-6650 975);
DISPLAY 0.680851 (-6650 975);
PAINT MONO (-6650 975);
DISPLAY INVISIBLE (-6650 975);
FORCEPROP 0 LAST CDS_SEC 1
J 0
(-6650 975);
DISPLAY 0.680851 (-6650 975);
DISPLAY INVISIBLE (-6650 975);
FORCEPROP 1 LASTPIN (-6700 925) $PN 1
J 0
(-6690 905);
DISPLAY 0.787234 (-6690 905);
PAINT MONO (-6690 905);
FORCEPROP 1 LASTPIN (-6700 725) $PN 2
J 0
(-6690 705);
DISPLAY 0.787234 (-6690 705);
PAINT MONO (-6690 705);
FORCEPROP 1 LAST MATERIAL COG
J 0
(-6650 725);
DISPLAY 0.638298 (-6650 725);
FORCEPROP 0 LAST ROOM USB3_HUB2
J 0
(-6650 1025);
DISPLAY 0.553191 (-6650 1025);
PAINT RED (-6650 1025);
FORCEPROP 1 LAST PACK_TYPE C0402
J 0
(-6650 625);
DISPLAY 0.638298 (-6650 625);
FORCEPROP 1 LAST VALUE 1PF
J 0
(-6650 875);
DISPLAY 0.638298 (-6650 875);
FORCEPROP 1 LAST VOLTAGE 50V
J 0
(-6650 825);
DISPLAY 0.638298 (-6650 825);
FORCEPROP 1 LAST TOLERANCE 0.05P
J 0
(-6650 775);
DISPLAY 0.638298 (-6650 775);
FORCEPROP 2 LAST CDS_LIB pure_quanta
J 0
(-6700 825);
DISPLAY INVISIBLE (-6700 825);
FORCEPROP 1 LAST PATH I41
J 0
(-6650 975);
DISPLAY 0.978723 (-6650 975);
PAINT WHITE (-6650 975);
DISPLAY INVISIBLE (-6650 975);
FORCEPROP 1 LAST PART_NUMBER CH-106T0B00
J 0
(-6650 675);
DISPLAY 0.638298 (-6650 675);
DISPLAY INVISIBLE (-6650 675);
FORCEADD Q_CAP..1
(-5175 850);
FORCEPROP 1 LAST LOCATION C6111
J 0
(-5125 950);
DISPLAY 0.638298 (-5125 950);
FORCEPROP 0 LAST $SEC 1
J 0
(-5125 1000);
DISPLAY 0.680851 (-5125 1000);
PAINT MONO (-5125 1000);
DISPLAY INVISIBLE (-5125 1000);
FORCEPROP 0 LAST CDS_SEC 1
J 0
(-5125 1000);
DISPLAY 0.680851 (-5125 1000);
DISPLAY INVISIBLE (-5125 1000);
FORCEPROP 1 LASTPIN (-5175 950) $PN 1
J 0
(-5165 930);
DISPLAY 0.787234 (-5165 930);
PAINT MONO (-5165 930);
FORCEPROP 1 LASTPIN (-5175 750) $PN 2
J 0
(-5165 730);
DISPLAY 0.787234 (-5165 730);
PAINT MONO (-5165 730);
FORCEPROP 1 LAST VALUE 0.1UF
J 0
(-5125 900);
DISPLAY 0.638298 (-5125 900);
FORCEPROP 1 LAST PACK_TYPE 0402
J 0
(-5125 650);
DISPLAY 0.638298 (-5125 650);
FORCEPROP 1 LAST MATERIAL X7R
J 0
(-5125 750);
DISPLAY 0.638298 (-5125 750);
FORCEPROP 1 LAST TOLERANCE 10%
J 0
(-5125 800);
DISPLAY 0.638298 (-5125 800);
FORCEPROP 0 LAST ROOM USB3_HUB2
J 0
(-5125 1050);
DISPLAY 0.446809 (-5125 1050);
PAINT RED (-5125 1050);
FORCEPROP 1 LAST VOLTAGE 25V
J 0
(-5125 850);
DISPLAY 0.638298 (-5125 850);
FORCEPROP 2 LAST CDS_LIB pure_quanta
J 0
(-5175 850);
DISPLAY INVISIBLE (-5175 850);
FORCEPROP 1 LAST PATH I42
J 0
(-5125 1000);
DISPLAY 0.978723 (-5125 1000);
PAINT WHITE (-5125 1000);
DISPLAY INVISIBLE (-5125 1000);
FORCEPROP 1 LAST PART_NUMBER CH4104K1B00
J 0
(-5125 700);
DISPLAY 0.808511 (-5125 700);
DISPLAY INVISIBLE (-5125 700);
FORCEADD Q_CAP..1
(-5450 825);
FORCEPROP 1 LAST LOCATION C6110
J 0
(-5400 925);
DISPLAY 0.638298 (-5400 925);
FORCEPROP 0 LAST $SEC 1
J 0
(-5400 975);
DISPLAY 0.680851 (-5400 975);
PAINT MONO (-5400 975);
DISPLAY INVISIBLE (-5400 975);
FORCEPROP 0 LAST CDS_SEC 1
J 0
(-5400 975);
DISPLAY 0.680851 (-5400 975);
DISPLAY INVISIBLE (-5400 975);
FORCEPROP 1 LASTPIN (-5450 925) $PN 1
J 0
(-5440 905);
DISPLAY 0.787234 (-5440 905);
PAINT MONO (-5440 905);
FORCEPROP 1 LASTPIN (-5450 725) $PN 2
J 0
(-5440 705);
DISPLAY 0.787234 (-5440 705);
PAINT MONO (-5440 705);
FORCEPROP 1 LAST PACK_TYPE C0402
J 0
(-5400 625);
DISPLAY 0.510638 (-5400 625);
FORCEPROP 0 LAST ROOM USB3_HUB2
J 0
(-5400 1025);
DISPLAY 0.446809 (-5400 1025);
PAINT RED (-5400 1025);
FORCEPROP 1 LAST TOLERANCE 10%
J 0
(-5400 775);
DISPLAY 0.510638 (-5400 775);
FORCEPROP 1 LAST MATERIAL X7R
J 0
(-5400 725);
DISPLAY 0.510638 (-5400 725);
FORCEPROP 1 LAST VOLTAGE 50V
J 0
(-5400 825);
DISPLAY 0.510638 (-5400 825);
FORCEPROP 1 LAST VALUE 0.01UF
J 0
(-5400 875);
DISPLAY 0.510638 (-5400 875);
FORCEPROP 2 LAST CDS_LIB pure_quanta
J 0
(-5450 825);
DISPLAY INVISIBLE (-5450 825);
FORCEPROP 1 LAST PATH I43
J 0
(-5400 975);
DISPLAY 0.978723 (-5400 975);
PAINT WHITE (-5400 975);
DISPLAY INVISIBLE (-5400 975);
FORCEPROP 1 LAST PART_NUMBER CH31006KB18
J 0
(-5400 675);
DISPLAY 0.638298 (-5400 675);
DISPLAY INVISIBLE (-5400 675);
FORCEADD Q_CAP..1
(-5750 850);
FORCEPROP 1 LAST LOCATION C6109
J 0
(-5700 950);
DISPLAY 0.638298 (-5700 950);
FORCEPROP 0 LAST $SEC 1
J 0
(-5700 1000);
DISPLAY 0.680851 (-5700 1000);
PAINT MONO (-5700 1000);
DISPLAY INVISIBLE (-5700 1000);
FORCEPROP 0 LAST CDS_SEC 1
J 0
(-5700 1000);
DISPLAY 0.680851 (-5700 1000);
DISPLAY INVISIBLE (-5700 1000);
FORCEPROP 1 LASTPIN (-5750 950) $PN 1
J 0
(-5740 930);
DISPLAY 0.787234 (-5740 930);
PAINT MONO (-5740 930);
FORCEPROP 1 LASTPIN (-5750 750) $PN 2
J 0
(-5740 730);
DISPLAY 0.787234 (-5740 730);
PAINT MONO (-5740 730);
FORCEPROP 1 LAST MATERIAL COG
J 0
(-5700 750);
DISPLAY 0.638298 (-5700 750);
FORCEPROP 1 LAST PACK_TYPE C0402
J 0
(-5700 650);
DISPLAY 0.638298 (-5700 650);
FORCEPROP 1 LAST VALUE 1PF
J 0
(-5700 900);
DISPLAY 0.638298 (-5700 900);
FORCEPROP 1 LAST VOLTAGE 50V
J 0
(-5700 850);
DISPLAY 0.638298 (-5700 850);
FORCEPROP 1 LAST TOLERANCE 0.05P
J 0
(-5700 800);
DISPLAY 0.638298 (-5700 800);
FORCEPROP 0 LAST ROOM USB3_HUB2
J 0
(-5700 1050);
DISPLAY 0.446809 (-5700 1050);
PAINT RED (-5700 1050);
FORCEPROP 2 LAST CDS_LIB pure_quanta
J 0
(-5750 850);
DISPLAY INVISIBLE (-5750 850);
FORCEPROP 1 LAST PATH I44
J 0
(-5700 1000);
DISPLAY 0.978723 (-5700 1000);
PAINT WHITE (-5700 1000);
DISPLAY INVISIBLE (-5700 1000);
FORCEPROP 1 LAST PART_NUMBER CH-106T0B00
J 0
(-5700 700);
DISPLAY 0.638298 (-5700 700);
DISPLAY INVISIBLE (-5700 700);
FORCEADD Q_CAP..1
(-4250 850);
FORCEPROP 1 LAST LOCATION C6114
J 0
(-4200 950);
DISPLAY 0.638298 (-4200 950);
FORCEPROP 0 LAST $SEC 1
J 0
(-4200 1000);
DISPLAY 0.680851 (-4200 1000);
PAINT MONO (-4200 1000);
DISPLAY INVISIBLE (-4200 1000);
FORCEPROP 0 LAST CDS_SEC 1
J 0
(-4200 1000);
DISPLAY 0.680851 (-4200 1000);
DISPLAY INVISIBLE (-4200 1000);
FORCEPROP 1 LASTPIN (-4250 950) $PN 1
J 0
(-4240 930);
DISPLAY 0.787234 (-4240 930);
PAINT MONO (-4240 930);
FORCEPROP 1 LASTPIN (-4250 750) $PN 2
J 0
(-4240 730);
DISPLAY 0.787234 (-4240 730);
PAINT MONO (-4240 730);
FORCEPROP 1 LAST PACK_TYPE 0402
J 0
(-4200 650);
DISPLAY 0.638298 (-4200 650);
FORCEPROP 0 LAST ROOM USB3_HUB2
J 0
(-4200 1050);
DISPLAY 0.553191 (-4200 1050);
PAINT RED (-4200 1050);
FORCEPROP 1 LAST VALUE 0.1UF
J 0
(-4200 900);
DISPLAY 0.638298 (-4200 900);
FORCEPROP 1 LAST VOLTAGE 25V
J 0
(-4200 850);
DISPLAY 0.638298 (-4200 850);
FORCEPROP 1 LAST MATERIAL X7R
J 0
(-4200 750);
DISPLAY 0.638298 (-4200 750);
FORCEPROP 1 LAST TOLERANCE 10%
J 0
(-4200 800);
DISPLAY 0.638298 (-4200 800);
FORCEPROP 2 LAST CDS_LIB pure_quanta
J 0
(-4250 850);
DISPLAY INVISIBLE (-4250 850);
FORCEPROP 1 LAST PATH I45
J 0
(-4200 1000);
DISPLAY 0.978723 (-4200 1000);
PAINT WHITE (-4200 1000);
DISPLAY INVISIBLE (-4200 1000);
FORCEPROP 1 LAST PART_NUMBER CH4104K1B00
J 0
(-4200 700);
DISPLAY 0.808511 (-4200 700);
DISPLAY INVISIBLE (-4200 700);
FORCEADD Q_CAP..1
(-4550 825);
FORCEPROP 1 LAST LOCATION C6113
J 0
(-4500 925);
DISPLAY 0.638298 (-4500 925);
FORCEPROP 0 LAST $SEC 1
J 0
(-4500 975);
DISPLAY 0.680851 (-4500 975);
PAINT MONO (-4500 975);
DISPLAY INVISIBLE (-4500 975);
FORCEPROP 0 LAST CDS_SEC 1
J 0
(-4500 975);
DISPLAY 0.680851 (-4500 975);
DISPLAY INVISIBLE (-4500 975);
FORCEPROP 1 LASTPIN (-4550 925) $PN 1
J 0
(-4540 905);
DISPLAY 0.787234 (-4540 905);
PAINT MONO (-4540 905);
FORCEPROP 1 LASTPIN (-4550 725) $PN 2
J 0
(-4540 705);
DISPLAY 0.787234 (-4540 705);
PAINT MONO (-4540 705);
FORCEPROP 1 LAST PACK_TYPE C0402
J 0
(-4500 625);
DISPLAY 0.510638 (-4500 625);
FORCEPROP 1 LAST MATERIAL X7R
J 0
(-4500 725);
DISPLAY 0.510638 (-4500 725);
FORCEPROP 1 LAST TOLERANCE 10%
J 0
(-4500 775);
DISPLAY 0.510638 (-4500 775);
FORCEPROP 0 LAST ROOM USB3_HUB2
J 0
(-4500 1025);
DISPLAY 0.553191 (-4500 1025);
PAINT RED (-4500 1025);
FORCEPROP 1 LAST VOLTAGE 50V
J 0
(-4500 825);
DISPLAY 0.510638 (-4500 825);
FORCEPROP 1 LAST VALUE 0.01UF
J 0
(-4500 875);
DISPLAY 0.510638 (-4500 875);
FORCEPROP 2 LAST CDS_LIB pure_quanta
J 0
(-4550 825);
DISPLAY INVISIBLE (-4550 825);
FORCEPROP 1 LAST PATH I46
J 0
(-4500 975);
DISPLAY 0.978723 (-4500 975);
PAINT WHITE (-4500 975);
DISPLAY INVISIBLE (-4500 975);
FORCEPROP 1 LAST PART_NUMBER CH31006KB18
J 0
(-4500 675);
DISPLAY 0.638298 (-4500 675);
DISPLAY INVISIBLE (-4500 675);
FORCEADD Q_CAP..1
(-4875 850);
FORCEPROP 1 LAST LOCATION C6112
J 0
(-4825 950);
DISPLAY 0.638298 (-4825 950);
FORCEPROP 0 LAST $SEC 1
J 0
(-4825 1000);
DISPLAY 0.680851 (-4825 1000);
PAINT MONO (-4825 1000);
DISPLAY INVISIBLE (-4825 1000);
FORCEPROP 0 LAST CDS_SEC 1
J 0
(-4825 1000);
DISPLAY 0.680851 (-4825 1000);
DISPLAY INVISIBLE (-4825 1000);
FORCEPROP 1 LASTPIN (-4875 950) $PN 1
J 0
(-4865 930);
DISPLAY 0.787234 (-4865 930);
PAINT MONO (-4865 930);
FORCEPROP 1 LASTPIN (-4875 750) $PN 2
J 0
(-4865 730);
DISPLAY 0.787234 (-4865 730);
PAINT MONO (-4865 730);
FORCEPROP 1 LAST MATERIAL COG
J 0
(-4825 750);
DISPLAY 0.638298 (-4825 750);
FORCEPROP 1 LAST PACK_TYPE C0402
J 0
(-4825 650);
DISPLAY 0.638298 (-4825 650);
FORCEPROP 1 LAST VALUE 1PF
J 0
(-4825 900);
DISPLAY 0.638298 (-4825 900);
FORCEPROP 0 LAST ROOM USB3_HUB2
J 0
(-4825 1050);
DISPLAY 0.553191 (-4825 1050);
PAINT RED (-4825 1050);
FORCEPROP 1 LAST TOLERANCE 0.05P
J 0
(-4825 800);
DISPLAY 0.638298 (-4825 800);
FORCEPROP 1 LAST VOLTAGE 50V
J 0
(-4825 850);
DISPLAY 0.638298 (-4825 850);
FORCEPROP 2 LAST CDS_LIB pure_quanta
J 0
(-4875 850);
DISPLAY INVISIBLE (-4875 850);
FORCEPROP 1 LAST PATH I47
J 0
(-4825 1000);
DISPLAY 0.978723 (-4825 1000);
PAINT WHITE (-4825 1000);
DISPLAY INVISIBLE (-4825 1000);
FORCEPROP 1 LAST PART_NUMBER CH-106T0B00
J 0
(-4825 700);
DISPLAY 0.638298 (-4825 700);
DISPLAY INVISIBLE (-4825 700);
FORCEADD Q_CAP..1
(-3400 850);
FORCEPROP 1 LAST LOCATION C6117
J 0
(-3350 950);
DISPLAY 0.638298 (-3350 950);
FORCEPROP 0 LAST $SEC 1
J 0
(-3350 1000);
DISPLAY 0.680851 (-3350 1000);
PAINT MONO (-3350 1000);
DISPLAY INVISIBLE (-3350 1000);
FORCEPROP 0 LAST CDS_SEC 1
J 0
(-3350 1000);
DISPLAY 0.680851 (-3350 1000);
DISPLAY INVISIBLE (-3350 1000);
FORCEPROP 1 LASTPIN (-3400 950) $PN 1
J 0
(-3390 930);
DISPLAY 0.787234 (-3390 930);
PAINT MONO (-3390 930);
FORCEPROP 1 LASTPIN (-3400 750) $PN 2
J 0
(-3390 730);
DISPLAY 0.787234 (-3390 730);
PAINT MONO (-3390 730);
FORCEPROP 1 LAST PACK_TYPE 0402
J 0
(-3350 650);
DISPLAY 0.638298 (-3350 650);
FORCEPROP 0 LAST ROOM USB3_HUB2
J 0
(-3350 1050);
DISPLAY 0.446809 (-3350 1050);
PAINT RED (-3350 1050);
FORCEPROP 1 LAST TOLERANCE 10%
J 0
(-3350 800);
DISPLAY 0.638298 (-3350 800);
FORCEPROP 1 LAST MATERIAL X7R
J 0
(-3350 750);
DISPLAY 0.638298 (-3350 750);
FORCEPROP 1 LAST VALUE 0.1UF
J 0
(-3350 900);
DISPLAY 0.638298 (-3350 900);
FORCEPROP 1 LAST VOLTAGE 25V
J 0
(-3350 850);
DISPLAY 0.638298 (-3350 850);
FORCEPROP 2 LAST CDS_LIB pure_quanta
J 0
(-3400 850);
DISPLAY INVISIBLE (-3400 850);
FORCEPROP 1 LAST PATH I48
J 0
(-3350 1000);
DISPLAY 0.978723 (-3350 1000);
PAINT WHITE (-3350 1000);
DISPLAY INVISIBLE (-3350 1000);
FORCEPROP 1 LAST PART_NUMBER CH4104K1B00
J 0
(-3350 700);
DISPLAY 0.808511 (-3350 700);
DISPLAY INVISIBLE (-3350 700);
FORCEADD Q_CAP..1
(-3675 850);
FORCEPROP 1 LAST LOCATION C6116
J 0
(-3625 950);
DISPLAY 0.638298 (-3625 950);
FORCEPROP 0 LAST $SEC 1
J 0
(-3625 1000);
DISPLAY 0.680851 (-3625 1000);
PAINT MONO (-3625 1000);
DISPLAY INVISIBLE (-3625 1000);
FORCEPROP 0 LAST CDS_SEC 1
J 0
(-3625 1000);
DISPLAY 0.680851 (-3625 1000);
DISPLAY INVISIBLE (-3625 1000);
FORCEPROP 1 LASTPIN (-3675 950) $PN 1
J 0
(-3665 930);
DISPLAY 0.787234 (-3665 930);
PAINT MONO (-3665 930);
FORCEPROP 1 LASTPIN (-3675 750) $PN 2
J 0
(-3665 730);
DISPLAY 0.787234 (-3665 730);
PAINT MONO (-3665 730);
FORCEPROP 1 LAST PACK_TYPE C0402
J 0
(-3625 650);
DISPLAY 0.510638 (-3625 650);
FORCEPROP 1 LAST VALUE 0.01UF
J 0
(-3625 900);
DISPLAY 0.510638 (-3625 900);
FORCEPROP 1 LAST TOLERANCE 10%
J 0
(-3625 800);
DISPLAY 0.510638 (-3625 800);
FORCEPROP 1 LAST MATERIAL X7R
J 0
(-3625 750);
DISPLAY 0.510638 (-3625 750);
FORCEPROP 1 LAST VOLTAGE 50V
J 0
(-3625 850);
DISPLAY 0.510638 (-3625 850);
FORCEPROP 0 LAST ROOM USB3_HUB2
J 0
(-3625 1050);
DISPLAY 0.446809 (-3625 1050);
PAINT RED (-3625 1050);
FORCEPROP 2 LAST CDS_LIB pure_quanta
J 0
(-3675 850);
DISPLAY INVISIBLE (-3675 850);
FORCEPROP 1 LAST PATH I49
J 0
(-3625 1000);
DISPLAY 0.978723 (-3625 1000);
PAINT WHITE (-3625 1000);
DISPLAY INVISIBLE (-3625 1000);
FORCEPROP 1 LAST PART_NUMBER CH31006KB18
J 0
(-3625 700);
DISPLAY 0.638298 (-3625 700);
DISPLAY INVISIBLE (-3625 700);
FORCEADD Q_CAP..1
(-3925 850);
FORCEPROP 1 LAST LOCATION C6115
J 0
(-3875 950);
DISPLAY 0.638298 (-3875 950);
FORCEPROP 0 LAST $SEC 1
J 0
(-3875 1000);
DISPLAY 0.680851 (-3875 1000);
PAINT MONO (-3875 1000);
DISPLAY INVISIBLE (-3875 1000);
FORCEPROP 0 LAST CDS_SEC 1
J 0
(-3875 1000);
DISPLAY 0.680851 (-3875 1000);
DISPLAY INVISIBLE (-3875 1000);
FORCEPROP 1 LASTPIN (-3925 950) $PN 1
J 0
(-3915 930);
DISPLAY 0.787234 (-3915 930);
PAINT MONO (-3915 930);
FORCEPROP 1 LASTPIN (-3925 750) $PN 2
J 0
(-3915 730);
DISPLAY 0.787234 (-3915 730);
PAINT MONO (-3915 730);
FORCEPROP 1 LAST PACK_TYPE C0402
J 0
(-3875 650);
DISPLAY 0.638298 (-3875 650);
FORCEPROP 1 LAST TOLERANCE 0.05P
J 0
(-3875 800);
DISPLAY 0.638298 (-3875 800);
FORCEPROP 0 LAST ROOM USB3_HUB2
J 0
(-3875 1050);
DISPLAY 0.446809 (-3875 1050);
PAINT RED (-3875 1050);
FORCEPROP 1 LAST MATERIAL COG
J 0
(-3875 750);
DISPLAY 0.638298 (-3875 750);
FORCEPROP 1 LAST VALUE 1PF
J 0
(-3875 900);
DISPLAY 0.638298 (-3875 900);
FORCEPROP 1 LAST VOLTAGE 50V
J 0
(-3875 850);
DISPLAY 0.638298 (-3875 850);
FORCEPROP 2 LAST CDS_LIB pure_quanta
J 0
(-3925 850);
DISPLAY INVISIBLE (-3925 850);
FORCEPROP 1 LAST PATH I50
J 0
(-3875 1000);
DISPLAY 0.978723 (-3875 1000);
PAINT WHITE (-3875 1000);
DISPLAY INVISIBLE (-3875 1000);
FORCEPROP 1 LAST PART_NUMBER CH-106T0B00
J 0
(-3875 700);
DISPLAY 0.638298 (-3875 700);
DISPLAY INVISIBLE (-3875 700);
FORCEADD Q_CAP..1
(-2200 850);
FORCEPROP 1 LAST LOCATION C6121
J 0
(-2150 950);
DISPLAY 0.638298 (-2150 950);
FORCEPROP 0 LAST $SEC 1
J 0
(-2150 1000);
DISPLAY 0.680851 (-2150 1000);
PAINT MONO (-2150 1000);
DISPLAY INVISIBLE (-2150 1000);
FORCEPROP 0 LAST CDS_SEC 1
J 0
(-2150 1000);
DISPLAY 0.680851 (-2150 1000);
DISPLAY INVISIBLE (-2150 1000);
FORCEPROP 1 LASTPIN (-2200 950) $PN 1
J 0
(-2190 930);
DISPLAY 0.787234 (-2190 930);
PAINT MONO (-2190 930);
FORCEPROP 1 LASTPIN (-2200 750) $PN 2
J 0
(-2190 730);
DISPLAY 0.787234 (-2190 730);
PAINT MONO (-2190 730);
FORCEPROP 1 LAST TOLERANCE 10%
J 0
(-2150 800);
DISPLAY 0.638298 (-2150 800);
FORCEPROP 1 LAST MATERIAL X7R
J 0
(-2150 750);
DISPLAY 0.638298 (-2150 750);
FORCEPROP 1 LAST VOLTAGE 25V
J 0
(-2150 850);
DISPLAY 0.638298 (-2150 850);
FORCEPROP 1 LAST PACK_TYPE 0402
J 0
(-2150 650);
DISPLAY 0.638298 (-2150 650);
FORCEPROP 1 LAST VALUE 0.1UF
J 0
(-2150 900);
DISPLAY 0.638298 (-2150 900);
FORCEPROP 0 LAST ROOM USB3_HUB2
J 0
(-2150 1050);
DISPLAY 0.680851 (-2150 1050);
PAINT RED (-2150 1050);
FORCEPROP 2 LAST CDS_LIB pure_quanta
J 0
(-2200 850);
DISPLAY INVISIBLE (-2200 850);
FORCEPROP 1 LAST PATH I51
J 0
(-2150 1000);
DISPLAY 0.978723 (-2150 1000);
PAINT WHITE (-2150 1000);
DISPLAY INVISIBLE (-2150 1000);
FORCEPROP 1 LAST PART_NUMBER CH4104K1B00
J 0
(-2150 700);
DISPLAY 0.808511 (-2150 700);
DISPLAY INVISIBLE (-2150 700);
FORCEADD Q_CAP..1
(-2450 850);
FORCEPROP 1 LAST LOCATION C6120
J 0
(-2400 950);
DISPLAY 0.638298 (-2400 950);
FORCEPROP 0 LAST $SEC 1
J 0
(-2400 1000);
DISPLAY 0.680851 (-2400 1000);
PAINT MONO (-2400 1000);
DISPLAY INVISIBLE (-2400 1000);
FORCEPROP 0 LAST CDS_SEC 1
J 0
(-2400 1000);
DISPLAY 0.680851 (-2400 1000);
DISPLAY INVISIBLE (-2400 1000);
FORCEPROP 1 LASTPIN (-2450 950) $PN 1
J 0
(-2440 930);
DISPLAY 0.787234 (-2440 930);
PAINT MONO (-2440 930);
FORCEPROP 1 LASTPIN (-2450 750) $PN 2
J 0
(-2440 730);
DISPLAY 0.787234 (-2440 730);
PAINT MONO (-2440 730);
FORCEPROP 1 LAST TOLERANCE 10%
J 0
(-2400 800);
DISPLAY 0.510638 (-2400 800);
FORCEPROP 1 LAST MATERIAL X7R
J 0
(-2400 750);
DISPLAY 0.510638 (-2400 750);
FORCEPROP 1 LAST PACK_TYPE C0402
J 0
(-2400 650);
DISPLAY 0.510638 (-2400 650);
FORCEPROP 1 LAST VALUE 0.01UF
J 0
(-2400 900);
DISPLAY 0.510638 (-2400 900);
FORCEPROP 1 LAST VOLTAGE 50V
J 0
(-2400 850);
DISPLAY 0.510638 (-2400 850);
FORCEPROP 0 LAST ROOM USB3_HUB2
J 0
(-2400 1050);
DISPLAY 0.446809 (-2400 1050);
PAINT RED (-2400 1050);
FORCEPROP 2 LAST CDS_LIB pure_quanta
J 0
(-2450 850);
DISPLAY INVISIBLE (-2450 850);
FORCEPROP 1 LAST PATH I52
J 0
(-2400 1000);
DISPLAY 0.978723 (-2400 1000);
PAINT WHITE (-2400 1000);
DISPLAY INVISIBLE (-2400 1000);
FORCEPROP 1 LAST PART_NUMBER CH31006KB18
J 0
(-2400 700);
DISPLAY 0.638298 (-2400 700);
DISPLAY INVISIBLE (-2400 700);
FORCEADD Q_CAP..1
(-2750 850);
FORCEPROP 1 LAST LOCATION C6119
J 0
(-2700 950);
DISPLAY 0.638298 (-2700 950);
FORCEPROP 0 LAST $SEC 1
J 0
(-2700 1000);
DISPLAY 0.680851 (-2700 1000);
PAINT MONO (-2700 1000);
DISPLAY INVISIBLE (-2700 1000);
FORCEPROP 0 LAST CDS_SEC 1
J 0
(-2700 1000);
DISPLAY 0.680851 (-2700 1000);
DISPLAY INVISIBLE (-2700 1000);
FORCEPROP 1 LASTPIN (-2750 950) $PN 1
J 0
(-2740 930);
DISPLAY 0.787234 (-2740 930);
PAINT MONO (-2740 930);
FORCEPROP 1 LASTPIN (-2750 750) $PN 2
J 0
(-2740 730);
DISPLAY 0.787234 (-2740 730);
PAINT MONO (-2740 730);
FORCEPROP 1 LAST PACK_TYPE C0402
J 0
(-2700 650);
DISPLAY 0.638298 (-2700 650);
FORCEPROP 1 LAST VALUE 1PF
J 0
(-2700 900);
DISPLAY 0.638298 (-2700 900);
FORCEPROP 1 LAST MATERIAL COG
J 0
(-2700 750);
DISPLAY 0.638298 (-2700 750);
FORCEPROP 1 LAST TOLERANCE 0.05P
J 0
(-2700 800);
DISPLAY 0.638298 (-2700 800);
FORCEPROP 1 LAST VOLTAGE 50V
J 0
(-2700 850);
DISPLAY 0.638298 (-2700 850);
FORCEPROP 0 LAST ROOM USB3_HUB2
J 0
(-2700 1050);
DISPLAY 0.553191 (-2700 1050);
PAINT RED (-2700 1050);
FORCEPROP 2 LAST CDS_LIB pure_quanta
J 0
(-2750 850);
DISPLAY INVISIBLE (-2750 850);
FORCEPROP 1 LAST PATH I53
J 0
(-2700 1000);
DISPLAY 0.978723 (-2700 1000);
PAINT WHITE (-2700 1000);
DISPLAY INVISIBLE (-2700 1000);
FORCEPROP 1 LAST PART_NUMBER CH-106T0B00
J 0
(-2700 700);
DISPLAY 0.638298 (-2700 700);
DISPLAY INVISIBLE (-2700 700);
FORCEADD Q_CAP..1
(-3125 825);
FORCEPROP 1 LAST LOCATION C6118
J 0
(-3075 925);
DISPLAY 0.765957 (-3075 925);
PAINT SKYBLUE (-3075 925);
FORCEPROP 0 LAST $SEC 1
J 0
(-3075 975);
DISPLAY 0.680851 (-3075 975);
PAINT MONO (-3075 975);
DISPLAY INVISIBLE (-3075 975);
FORCEPROP 0 LAST CDS_SEC 1
J 0
(-3075 975);
DISPLAY 0.680851 (-3075 975);
DISPLAY INVISIBLE (-3075 975);
FORCEPROP 1 LASTPIN (-3125 925) $PN 1
J 0
(-3115 905);
DISPLAY 0.787234 (-3115 905);
PAINT MONO (-3115 905);
FORCEPROP 1 LASTPIN (-3125 725) $PN 2
J 0
(-3115 705);
DISPLAY 0.787234 (-3115 705);
PAINT MONO (-3115 705);
FORCEPROP 1 LAST PACK_TYPE C0805
J 0
(-3075 625);
DISPLAY 0.617021 (-3075 625);
PAINT SKYBLUE (-3075 625);
FORCEPROP 1 LAST VOLTAGE 25V
J 0
(-3075 825);
DISPLAY 0.617021 (-3075 825);
PAINT SKYBLUE (-3075 825);
FORCEPROP 1 LAST TOLERANCE 10%
J 0
(-3075 775);
DISPLAY 0.617021 (-3075 775);
PAINT SKYBLUE (-3075 775);
FORCEPROP 1 LAST MATERIAL X6S
J 0
(-3075 725);
DISPLAY 0.617021 (-3075 725);
PAINT SKYBLUE (-3075 725);
FORCEPROP 1 LAST VALUE 10UF
J 0
(-3075 875);
DISPLAY 0.617021 (-3075 875);
PAINT SKYBLUE (-3075 875);
FORCEPROP 0 LAST ROOM USB3_HUB2
J 0
(-3075 1025);
DISPLAY 0.680851 (-3075 1025);
PAINT RED (-3075 1025);
FORCEPROP 2 LAST CDS_LIB pure_quanta
J 0
(-3125 825);
DISPLAY INVISIBLE (-3125 825);
FORCEPROP 1 LAST PATH I54
J 0
(-3075 975);
DISPLAY 0.978723 (-3075 975);
PAINT WHITE (-3075 975);
DISPLAY INVISIBLE (-3075 975);
FORCEPROP 1 LAST PART_NUMBER CH6104KEA00
J 0
(-3075 675);
DISPLAY 0.617021 (-3075 675);
PAINT SKYBLUE (-3075 675);
DISPLAY INVISIBLE (-3075 675);
FORCEADD GND..1
(-8200 3250);
FORCEPROP 3 LASTPIN (-8200 3300) SIG_NAME GND\g
J 0
(-8190 3310);
DISPLAY 0.659574 (-8190 3310);
PAINT MONO (-8190 3310);
DISPLAY INVISIBLE (-8190 3310);
FORCEPROP 2 LAST CDS_LIB pure_quanta_power
J 0
(-8200 3250);
DISPLAY INVISIBLE (-8200 3250);
FORCEPROP 1 LAST SIZE 1B
J 0
(-8125 3200);
DISPLAY 1.170213 (-8125 3200);
PAINT AQUA (-8125 3200);
DISPLAY INVISIBLE (-8125 3200);
FORCEPROP 1 LAST HDL_POWER GND
J 0
(-8200 3400);
DISPLAY 1.170213 (-8200 3400);
PAINT GREEN (-8200 3400);
DISPLAY INVISIBLE (-8200 3400);
FORCEPROP 1 LAST PATH I61
J 0
(-8125 3250);
DISPLAY 0.872340 (-8125 3250);
PAINT AQUA (-8125 3250);
DISPLAY INVISIBLE (-8125 3250);
FORCEADD Q_RES..2
(-8200 3925);
FORCEPROP 1 LAST LOCATION R6283
J 0
(-8155 4050);
DISPLAY 0.638298 (-8155 4050);
FORCEPROP 0 LAST $SEC 1
J 0
(-8150 4100);
DISPLAY 0.680851 (-8150 4100);
PAINT MONO (-8150 4100);
DISPLAY INVISIBLE (-8150 4100);
FORCEPROP 0 LAST CDS_SEC 1
J 0
(-8150 4100);
DISPLAY 0.680851 (-8150 4100);
DISPLAY INVISIBLE (-8150 4100);
FORCEPROP 1 LASTPIN (-8200 4025) $PN 1
J 0
(-8195 3987);
DISPLAY 0.787234 (-8195 3987);
PAINT MONO (-8195 3987);
FORCEPROP 1 LASTPIN (-8200 3825) $PN 2
J 0
(-8195 3835);
DISPLAY 0.787234 (-8195 3835);
PAINT MONO (-8195 3835);
FORCEPROP 1 LAST PACK_TYPE 0402LF
J 0
(-8160 3750);
DISPLAY 0.638298 (-8160 3750);
FORCEPROP 1 LAST WATTAGE 1/16W
J 0
(-8160 3900);
DISPLAY 0.638298 (-8160 3900);
FORCEPROP 2 LAST ROOM USB3_HUB2_TI
J 0
(-8175 4100);
DISPLAY 0.553191 (-8175 4100);
PAINT RED (-8175 4100);
FORCEPROP 1 LAST TOLERANCE 1%
J 0
(-8155 3950);
DISPLAY 0.638298 (-8155 3950);
FORCEPROP 1 LAST VALUE 1K
J 0
(-8155 4000);
DISPLAY 0.638298 (-8155 4000);
FORCEPROP 1 LAST MATERIAL EMPTY
J 0
(-8160 3850);
DISPLAY 0.638298 (-8160 3850);
FORCEPROP 2 LAST CDS_LIB pure_quanta
J 0
(-8200 3925);
DISPLAY INVISIBLE (-8200 3925);
FORCEPROP 1 LAST PATH I63
J 0
(-8150 4100);
DISPLAY 0.978723 (-8150 4100);
PAINT WHITE (-8150 4100);
DISPLAY INVISIBLE (-8150 4100);
FORCEPROP 1 LAST PART_NUMBER CS21002FB06
J 0
(-8160 3800);
DISPLAY 0.638298 (-8160 3800);
DISPLAY INVISIBLE (-8160 3800);
FORCEADD UNIVERSAL_POWER..1
(-8200 4175);
FORCEPROP 3 LASTPIN (-8200 4125) SIG_NAME P3V3_AUX\g
J 0
(-8190 4135);
DISPLAY 0.659574 (-8190 4135);
PAINT MONO (-8190 4135);
DISPLAY INVISIBLE (-8190 4135);
FORCEPROP 1 LAST HDL_POWER P3V3_AUX
J 1
(-8200 4225);
DISPLAY 0.489362 (-8200 4225);
PAINT GREEN (-8200 4225);
FORCEPROP 2 LAST CDS_LIB pure_quanta_power
J 0
(-8200 4175);
DISPLAY INVISIBLE (-8200 4175);
FORCEPROP 2 LAST BOM_COST VR_SYSTEM
J 0
(-8200 4275);
DISPLAY 0.617021 (-8200 4275);
PAINT PURPLE (-8200 4275);
DISPLAY INVISIBLE (-8200 4275);
FORCEPROP 1 LAST PATH I64
J 0
(-8150 4200);
DISPLAY 0.872340 (-8150 4200);
PAINT AQUA (-8150 4200);
DISPLAY INVISIBLE (-8150 4200);
FORCEADD OFFPAGE..2
R 2
(-5125 2725);
FORCEPROP 2 LAST $XR0 179 
J 0
(-5380 2725);
DISPLAY 0.638298 (-5380 2725);
PAINT MONO (-5380 2725);
FORCEPROP 2 LAST CDS_LIB standard
J 2
(-5125 2725);
DISPLAY INVISIBLE (-5125 2725);
FORCEPROP 1 LAST OFFPAGE TRUE
J 2
(-5450 2600);
DISPLAY 0.872340 (-5450 2600);
PAINT GREEN (-5450 2600);
DISPLAY INVISIBLE (-5450 2600);
FORCEPROP 1 LAST COMMENT_BODY TRUE
J 2
(-5080 2630);
DISPLAY 0.872340 (-5080 2630);
PAINT GREEN (-5080 2630);
DISPLAY INVISIBLE (-5080 2630);
FORCEPROP 2 LAST PATH I74
J 2
(-5300 2800);
DISPLAY 0.680851 (-5300 2800);
DISPLAY INVISIBLE (-5300 2800);
FORCEADD Q_RES..1
(-3550 2300);
FORCEPROP 1 LAST LOCATION R6291
J 0
(-3875 2300);
DISPLAY 0.808511 (-3875 2300);
FORCEPROP 0 LAST $SEC 1
J 0
(-3100 2350);
DISPLAY 0.680851 (-3100 2350);
PAINT MONO (-3100 2350);
DISPLAY INVISIBLE (-3100 2350);
FORCEPROP 0 LAST CDS_SEC 1
J 0
(-3100 2350);
DISPLAY 0.680851 (-3100 2350);
DISPLAY INVISIBLE (-3100 2350);
FORCEPROP 1 LASTPIN (-3650 2300) $PN 1
J 0
(-3638 2312);
DISPLAY 0.787234 (-3638 2312);
PAINT MONO (-3638 2312);
FORCEPROP 1 LASTPIN (-3450 2300) $PN 2
J 0
(-3488 2312);
DISPLAY 0.787234 (-3488 2312);
PAINT MONO (-3488 2312);
FORCEPROP 1 LAST MATERIAL CHIP
J 0
(-3600 2250);
DISPLAY 0.617021 (-3600 2250);
FORCEPROP 2 LAST ROOM USB3_HUB2_MRP
J 0
(-3725 2375);
DISPLAY 0.680851 (-3725 2375);
PAINT RED (-3725 2375);
FORCEPROP 1 LAST TOLERANCE 5%
J 0
(-3450 2250);
DISPLAY 0.617021 (-3450 2250);
FORCEPROP 1 LAST PACK_TYPE 0402LF
J 0
(-3375 2250);
DISPLAY 0.617021 (-3375 2250);
FORCEPROP 1 LAST VALUE 0
J 2
(-3625 2250);
DISPLAY 0.617021 (-3625 2250);
FORCEPROP 2 LAST CDS_LIB pure_quanta
J 0
(-3550 2300);
DISPLAY INVISIBLE (-3550 2300);
FORCEPROP 1 LAST WATTAGE 1/16W
J 2
(-3350 2250);
DISPLAY 0.617021 (-3350 2250);
DISPLAY INVISIBLE (-3350 2250);
FORCEPROP 2 LAST BOM_COST VR_SYSTEM 
J 0
(-3600 2450);
DISPLAY 0.680851 (-3600 2450);
DISPLAY INVISIBLE (-3600 2450);
FORCEPROP 1 LAST PATH I75
J 0
(-3600 2450);
DISPLAY 0.978723 (-3600 2450);
PAINT WHITE (-3600 2450);
DISPLAY INVISIBLE (-3600 2450);
FORCEPROP 1 LAST PART_NUMBER CS00002JB13
J 0
(-3700 2350);
DISPLAY 0.617021 (-3700 2350);
DISPLAY INVISIBLE (-3700 2350);
FORCEADD Q_RES..1
(-3575 2725);
FORCEPROP 1 LAST LOCATION R6290
J 0
(-3850 2725);
DISPLAY 0.808511 (-3850 2725);
FORCEPROP 0 LAST $SEC 1
J 0
(-3700 2825);
DISPLAY 0.680851 (-3700 2825);
PAINT MONO (-3700 2825);
DISPLAY INVISIBLE (-3700 2825);
FORCEPROP 0 LAST CDS_SEC 1
J 0
(-3700 2825);
DISPLAY 0.680851 (-3700 2825);
DISPLAY INVISIBLE (-3700 2825);
FORCEPROP 1 LASTPIN (-3675 2725) $PN 1
J 0
(-3663 2737);
DISPLAY 0.787234 (-3663 2737);
PAINT MONO (-3663 2737);
FORCEPROP 1 LASTPIN (-3475 2725) $PN 2
J 0
(-3513 2737);
DISPLAY 0.787234 (-3513 2737);
PAINT MONO (-3513 2737);
FORCEPROP 2 LAST ROOM USB3_HUB2_TI
J 0
(-3775 2800);
DISPLAY 0.680851 (-3775 2800);
PAINT RED (-3775 2800);
FORCEPROP 1 LAST MATERIAL CHIP
J 0
(-3450 2750);
DISPLAY 0.617021 (-3450 2750);
FORCEPROP 1 LAST PACK_TYPE 0402LF
J 0
(-3625 2675);
DISPLAY 0.617021 (-3625 2675);
FORCEPROP 1 LAST TOLERANCE 5%
J 0
(-3425 2675);
DISPLAY 0.617021 (-3425 2675);
FORCEPROP 1 LAST VALUE 0
J 2
(-3675 2675);
DISPLAY 0.617021 (-3675 2675);
FORCEPROP 2 LAST CDS_LIB pure_quanta
J 0
(-3575 2725);
DISPLAY INVISIBLE (-3575 2725);
FORCEPROP 2 LAST BOM_COST VR_SYSTEM 
J 0
(-3625 2875);
DISPLAY 0.680851 (-3625 2875);
DISPLAY INVISIBLE (-3625 2875);
FORCEPROP 1 LAST WATTAGE 1/16W
J 2
(-3375 2675);
DISPLAY 0.617021 (-3375 2675);
DISPLAY INVISIBLE (-3375 2675);
FORCEPROP 1 LAST PATH I76
J 0
(-3625 2875);
DISPLAY 0.978723 (-3625 2875);
PAINT WHITE (-3625 2875);
DISPLAY INVISIBLE (-3625 2875);
FORCEPROP 1 LAST PART_NUMBER CS00002JB13
J 0
(-3725 2775);
DISPLAY 0.617021 (-3725 2775);
DISPLAY INVISIBLE (-3725 2775);
FORCEADD Q_RES..2
(-1925 3000);
FORCEPROP 1 LAST LOCATION R6292
J 0
(-1880 3125);
DISPLAY 0.638298 (-1880 3125);
FORCEPROP 0 LAST $SEC 1
J 0
(-1875 3175);
DISPLAY 0.680851 (-1875 3175);
PAINT MONO (-1875 3175);
DISPLAY INVISIBLE (-1875 3175);
FORCEPROP 0 LAST CDS_SEC 1
J 0
(-1875 3175);
DISPLAY 0.680851 (-1875 3175);
DISPLAY INVISIBLE (-1875 3175);
FORCEPROP 1 LASTPIN (-1925 3100) $PN 1
J 0
(-1920 3062);
DISPLAY 0.787234 (-1920 3062);
PAINT MONO (-1920 3062);
FORCEPROP 1 LASTPIN (-1925 2900) $PN 2
J 0
(-1920 2910);
DISPLAY 0.787234 (-1920 2910);
PAINT MONO (-1920 2910);
FORCEPROP 2 LAST ROOM USB3_HUB2_TI
J 0
(-1875 2775);
DISPLAY 0.680851 (-1875 2775);
PAINT RED (-1875 2775);
FORCEPROP 1 LAST PACK_TYPE 0402LF
J 0
(-1885 2825);
DISPLAY 0.638298 (-1885 2825);
FORCEPROP 1 LAST VALUE 1K
J 0
(-1880 3075);
DISPLAY 0.638298 (-1880 3075);
FORCEPROP 1 LAST MATERIAL EMPTY
J 0
(-1885 2925);
DISPLAY 0.638298 (-1885 2925);
FORCEPROP 1 LAST TOLERANCE 1%
J 0
(-1880 3025);
DISPLAY 0.638298 (-1880 3025);
FORCEPROP 1 LAST WATTAGE 1/16W
J 0
(-1885 2975);
DISPLAY 0.638298 (-1885 2975);
FORCEPROP 2 LAST CDS_LIB pure_quanta
J 0
(-1925 3000);
DISPLAY INVISIBLE (-1925 3000);
FORCEPROP 1 LAST PATH I77
J 0
(-1875 3175);
DISPLAY 0.978723 (-1875 3175);
PAINT WHITE (-1875 3175);
DISPLAY INVISIBLE (-1875 3175);
FORCEPROP 1 LAST PART_NUMBER CS21002FB06
J 0
(-1885 2875);
DISPLAY 0.638298 (-1885 2875);
DISPLAY INVISIBLE (-1885 2875);
FORCEADD UNIVERSAL_POWER..1
(-1925 3275);
FORCEPROP 3 LASTPIN (-1925 3225) SIG_NAME P3V3_AUX\g
J 0
(-1915 3235);
DISPLAY 0.659574 (-1915 3235);
PAINT MONO (-1915 3235);
DISPLAY INVISIBLE (-1915 3235);
FORCEPROP 1 LAST HDL_POWER P3V3_AUX
J 1
(-1925 3325);
DISPLAY 0.489362 (-1925 3325);
PAINT GREEN (-1925 3325);
FORCEPROP 2 LAST BOM_COST VR_SYSTEM
J 0
(-1925 3375);
DISPLAY 0.617021 (-1925 3375);
PAINT PURPLE (-1925 3375);
DISPLAY INVISIBLE (-1925 3375);
FORCEPROP 2 LAST CDS_LIB pure_quanta_power
J 0
(-1925 3275);
DISPLAY INVISIBLE (-1925 3275);
FORCEPROP 1 LAST PATH I78
J 0
(-1875 3300);
DISPLAY 0.872340 (-1875 3300);
PAINT AQUA (-1875 3300);
DISPLAY INVISIBLE (-1875 3300);
FORCEADD Q_RES..2
(-1925 2525);
FORCEPROP 1 LAST LOCATION R6293
J 0
(-1880 2650);
DISPLAY 0.978723 (-1880 2650);
FORCEPROP 0 LAST $SEC 1
J 0
(-1875 2700);
DISPLAY 0.680851 (-1875 2700);
PAINT MONO (-1875 2700);
DISPLAY INVISIBLE (-1875 2700);
FORCEPROP 0 LAST CDS_SEC 1
J 0
(-1875 2700);
DISPLAY 0.680851 (-1875 2700);
DISPLAY INVISIBLE (-1875 2700);
FORCEPROP 1 LASTPIN (-1925 2625) $PN 1
J 0
(-1920 2587);
DISPLAY 0.787234 (-1920 2587);
PAINT MONO (-1920 2587);
FORCEPROP 1 LASTPIN (-1925 2425) $PN 2
J 0
(-1920 2435);
DISPLAY 0.787234 (-1920 2435);
PAINT MONO (-1920 2435);
FORCEPROP 2 LAST ROOM USB3_HUB2_TI
J 0
(-1900 2300);
DISPLAY 0.680851 (-1900 2300);
PAINT RED (-1900 2300);
FORCEPROP 1 LAST WATTAGE 1/16W
J 0
(-1885 2500);
DISPLAY 0.978723 (-1885 2500);
FORCEPROP 1 LAST MATERIAL CHIP
J 0
(-1885 2450);
DISPLAY 0.978723 (-1885 2450);
FORCEPROP 1 LAST PACK_TYPE 0402LF
J 0
(-1885 2350);
DISPLAY 0.978723 (-1885 2350);
FORCEPROP 1 LAST VALUE 4.7K
J 0
(-1880 2600);
DISPLAY 0.978723 (-1880 2600);
FORCEPROP 1 LAST TOLERANCE 1%
J 0
(-1880 2550);
DISPLAY 0.978723 (-1880 2550);
FORCEPROP 2 LAST CDS_LIB pure_quanta
J 0
(-1925 2525);
DISPLAY INVISIBLE (-1925 2525);
FORCEPROP 1 LAST PATH I79
J 0
(-1875 2700);
DISPLAY 0.978723 (-1875 2700);
PAINT WHITE (-1875 2700);
DISPLAY INVISIBLE (-1875 2700);
FORCEPROP 1 LAST PART_NUMBER CS24702FB06
J 0
(-1885 2400);
DISPLAY 0.787234 (-1885 2400);
DISPLAY INVISIBLE (-1885 2400);
FORCEADD GND..1
(-1925 2275);
FORCEPROP 3 LASTPIN (-1925 2325) SIG_NAME GND\g
J 0
(-1915 2335);
DISPLAY 0.659574 (-1915 2335);
PAINT MONO (-1915 2335);
DISPLAY INVISIBLE (-1915 2335);
FORCEPROP 2 LAST CDS_LIB pure_quanta_power
J 0
(-1925 2275);
DISPLAY INVISIBLE (-1925 2275);
FORCEPROP 1 LAST SIZE 1B
J 0
(-1850 2225);
DISPLAY 1.170213 (-1850 2225);
PAINT AQUA (-1850 2225);
DISPLAY INVISIBLE (-1850 2225);
FORCEPROP 1 LAST HDL_POWER GND
J 0
(-1925 2425);
DISPLAY 1.170213 (-1925 2425);
PAINT GREEN (-1925 2425);
DISPLAY INVISIBLE (-1925 2425);
FORCEPROP 1 LAST PATH I80
J 0
(-1850 2275);
DISPLAY 0.872340 (-1850 2275);
PAINT AQUA (-1850 2275);
DISPLAY INVISIBLE (-1850 2275);
FORCEADD Q_RES..2
(-2400 2425);
FORCEPROP 1 LAST LOCATION R6294
J 0
(-2355 2550);
DISPLAY 0.638298 (-2355 2550);
FORCEPROP 0 LAST $SEC 1
J 0
(-2350 2600);
DISPLAY 0.680851 (-2350 2600);
PAINT MONO (-2350 2600);
DISPLAY INVISIBLE (-2350 2600);
FORCEPROP 0 LAST CDS_SEC 1
J 0
(-2350 2600);
DISPLAY 0.680851 (-2350 2600);
DISPLAY INVISIBLE (-2350 2600);
FORCEPROP 1 LASTPIN (-2400 2525) $PN 1
J 0
(-2395 2487);
DISPLAY 0.787234 (-2395 2487);
PAINT MONO (-2395 2487);
FORCEPROP 1 LASTPIN (-2400 2325) $PN 2
J 0
(-2395 2335);
DISPLAY 0.787234 (-2395 2335);
PAINT MONO (-2395 2335);
FORCEPROP 2 LAST ROOM USB3_HUB2_MRP
J 0
(-2475 2200);
DISPLAY 0.680851 (-2475 2200);
PAINT RED (-2475 2200);
FORCEPROP 1 LAST WATTAGE 1/16W
J 0
(-2360 2400);
DISPLAY 0.510638 (-2360 2400);
FORCEPROP 1 LAST TOLERANCE 1%
J 0
(-2355 2450);
DISPLAY 0.510638 (-2355 2450);
FORCEPROP 1 LAST MATERIAL CHIP
J 0
(-2360 2350);
DISPLAY 0.510638 (-2360 2350);
FORCEPROP 1 LAST VALUE 10K
J 0
(-2355 2500);
DISPLAY 0.510638 (-2355 2500);
FORCEPROP 1 LAST PACK_TYPE 0402LF
J 0
(-2360 2250);
DISPLAY 0.510638 (-2360 2250);
FORCEPROP 2 LAST CDS_LIB pure_quanta
J 2
(-2400 2425);
DISPLAY INVISIBLE (-2400 2425);
FORCEPROP 1 LAST PATH I81
J 0
(-2350 2600);
DISPLAY 0.978723 (-2350 2600);
PAINT WHITE (-2350 2600);
DISPLAY INVISIBLE (-2350 2600);
FORCEPROP 1 LAST PART_NUMBER CS31002FB08
J 0
(-2360 2300);
DISPLAY 0.510638 (-2360 2300);
DISPLAY INVISIBLE (-2360 2300);
FORCEADD UNIVERSAL_POWER..1
(-2400 2625);
FORCEPROP 3 LASTPIN (-2400 2575) SIG_NAME P3V3_AUX\g
J 0
(-2390 2585);
DISPLAY 0.659574 (-2390 2585);
PAINT MONO (-2390 2585);
DISPLAY INVISIBLE (-2390 2585);
FORCEPROP 1 LAST HDL_POWER P3V3_AUX
J 1
(-2400 2675);
DISPLAY 0.489362 (-2400 2675);
PAINT GREEN (-2400 2675);
FORCEPROP 2 LAST CDS_LIB pure_quanta_power
J 0
(-2400 2625);
DISPLAY INVISIBLE (-2400 2625);
FORCEPROP 2 LAST BOM_COST VR_SYSTEM
J 0
(-2400 2725);
DISPLAY 0.617021 (-2400 2725);
PAINT PURPLE (-2400 2725);
DISPLAY INVISIBLE (-2400 2725);
FORCEPROP 1 LAST PATH I82
J 0
(-2350 2650);
DISPLAY 0.872340 (-2350 2650);
PAINT AQUA (-2350 2650);
DISPLAY INVISIBLE (-2350 2650);
FORCEADD DNS..1
(-8700 5475);
PAINT RED (-8700 5475);
FORCEPROP 2 LAST CDS_LIB mstr_misc
J 0
(-8700 5475);
DISPLAY INVISIBLE (-8700 5475);
FORCEPROP 2 LAST BOM_COST VR_SYSTEM 
J 0
(-8875 5650);
DISPLAY 0.680851 (-8875 5650);
DISPLAY INVISIBLE (-8875 5650);
FORCEPROP 1 LAST COMMENT_BODY TRUE
J 0
(-8700 5475);
DISPLAY INVISIBLE (-8700 5475);
FORCEADD DNS..1
(-8750 5975);
PAINT RED (-8750 5975);
FORCEPROP 2 LAST BOM_COST VR_SYSTEM 
J 0
(-8925 6150);
DISPLAY 0.680851 (-8925 6150);
DISPLAY INVISIBLE (-8925 6150);
FORCEPROP 2 LAST CDS_LIB mstr_misc
J 0
(-8750 5975);
DISPLAY INVISIBLE (-8750 5975);
FORCEPROP 1 LAST COMMENT_BODY TRUE
J 0
(-8750 5975);
DISPLAY INVISIBLE (-8750 5975);
FORCEADD DNS..1
(-8600 4550);
PAINT RED (-8600 4550);
FORCEPROP 2 LAST BOM_COST VR_SYSTEM 
J 0
(-8775 4725);
DISPLAY 0.680851 (-8775 4725);
DISPLAY INVISIBLE (-8775 4725);
FORCEPROP 2 LAST CDS_LIB mstr_misc
J 0
(-8600 4550);
DISPLAY INVISIBLE (-8600 4550);
FORCEPROP 1 LAST COMMENT_BODY TRUE
J 0
(-8600 4550);
DISPLAY INVISIBLE (-8600 4550);
FORCEADD DNS..1
(-8150 4000);
PAINT RED (-8150 4000);
FORCEPROP 2 LAST BOM_COST VR_SYSTEM 
J 0
(-8325 4175);
DISPLAY 0.680851 (-8325 4175);
DISPLAY INVISIBLE (-8325 4175);
FORCEPROP 2 LAST CDS_LIB mstr_misc
J 0
(-8150 4000);
DISPLAY INVISIBLE (-8150 4000);
FORCEPROP 1 LAST COMMENT_BODY TRUE
J 0
(-8150 4000);
DISPLAY INVISIBLE (-8150 4000);
FORCEADD DNS..1
(-1875 2950);
PAINT RED (-1875 2950);
FORCEPROP 2 LAST BOM_COST VR_SYSTEM 
J 0
(-2050 3125);
DISPLAY 0.680851 (-2050 3125);
DISPLAY INVISIBLE (-2050 3125);
FORCEPROP 2 LAST CDS_LIB mstr_misc
J 0
(-1875 2950);
DISPLAY INVISIBLE (-1875 2950);
FORCEPROP 1 LAST COMMENT_BODY TRUE
J 0
(-1875 2950);
DISPLAY INVISIBLE (-1875 2950);
FORCEADD DNS..1
(-500 3375);
PAINT RED (-500 3375);
FORCEPROP 2 LAST CDS_LIB mstr_misc
J 0
(-500 3375);
DISPLAY INVISIBLE (-500 3375);
FORCEPROP 2 LAST BOM_COST VR_SYSTEM 
J 0
(-675 3550);
DISPLAY 0.680851 (-675 3550);
DISPLAY INVISIBLE (-675 3550);
FORCEPROP 1 LAST COMMENT_BODY TRUE
J 0
(-500 3375);
DISPLAY INVISIBLE (-500 3375);
FORCEADD DNS..1
(-475 3750);
PAINT RED (-475 3750);
FORCEPROP 2 LAST CDS_LIB mstr_misc
J 0
(-475 3750);
DISPLAY INVISIBLE (-475 3750);
FORCEPROP 2 LAST BOM_COST VR_SYSTEM 
J 0
(-650 3925);
DISPLAY 0.680851 (-650 3925);
DISPLAY INVISIBLE (-650 3925);
FORCEPROP 1 LAST COMMENT_BODY TRUE
J 0
(-475 3750);
DISPLAY INVISIBLE (-475 3750);
FORCEADD DNS..1
(-9075 4675);
PAINT RED (-9075 4675);
FORCEPROP 2 LAST BOM_COST VR_SYSTEM 
J 0
(-9250 4850);
DISPLAY 0.680851 (-9250 4850);
DISPLAY INVISIBLE (-9250 4850);
FORCEPROP 2 LAST CDS_LIB mstr_misc
J 0
(-9075 4675);
DISPLAY INVISIBLE (-9075 4675);
FORCEPROP 1 LAST COMMENT_BODY TRUE
J 0
(-9075 4675);
DISPLAY INVISIBLE (-9075 4675);
FORCEADD QUANTA_TITLE_BLOCK_C..1
(0 0);
FORCEPROP 0 LAST CDS_CON_LAST_MODIFIED Thu Sep 14 16:12:47 2023
J 0
(-1885 15);
DISPLAY INVISIBLE (-1885 15);
FORCEPROP 1 LAST CUSTOM_TXT_CDS <CON_LAST_MODIFIED>
J 0
(-1885 15);
DISPLAY 0.978723 (-1885 15);
FORCEPROP 2 LAST CUSTOM_TXT_CDS <XR_PAGE_TITLE>
J 0
(-7890 5250);
DISPLAY 0.638298 (-7890 5250);
PAINT PINK (-7890 5250);
DISPLAY INVISIBLE (-7890 5250);
FORCEPROP 1 LAST CUSTOM_TXT_CDS <NAME_2>
J 0
(-3175 50);
FORCEPROP 1 LAST CUSTOM_TXT_CDS <NAME_1>
J 0
(-3175 175);
FORCEPROP 1 LAST CUSTOM_TXT_CDS <Q_NUMBER>
J 0
(-1403 103);
DISPLAY 1.212766 (-1403 103);
FORCEPROP 1 LAST CUSTOM_TXT_CDS <Q_PROJ>
J 0
(-2382 102);
DISPLAY 1.212766 (-2382 102);
FORCEPROP 1 LAST CUSTOM_TXT_CDS <Q_REV>
J 0
(-184 103);
DISPLAY 1.212766 (-184 103);
FORCEPROP 1 LAST CUSTOM_TXT_CDS <CON_PAGE_NUM> OF <CON_TOTAL_PAGES>
J 0
(-446 18);
DISPLAY 0.978723 (-446 18);
FORCEPROP 1 LAST Q_TITLE USB3.0 EXT HUB 2ND(2/2)
J 0
(-9250 100);
DISPLAY 2.446809 (-9250 100);
PAINT GREEN (-9250 100);
FORCEPROP 1 LAST CDS_LMAN_SYM_OUTLINE -9475,6775,100,-125
J 0
(0 0);
DISPLAY 0.468085 (0 0);
PAINT GREEN (0 0);
DISPLAY INVISIBLE (0 0);
FORCEPROP 2 LAST CDS_LIB pure_quanta
J 0
(0 0);
DISPLAY INVISIBLE (0 0);
FORCEPROP 2 LAST PAGE_BORDER TRUE
J 0
(-7890 5250);
DISPLAY 0.638298 (-7890 5250);
PAINT PINK (-7890 5250);
DISPLAY INVISIBLE (-7890 5250);
FORCEPROP 2 LAST CDS_XR_PAGE_TITLE CR-179 : @T6G_MB_LIB.T6G(SCH_1):PAGE179
J 0
(-7890 5250);
DISPLAY 0.638298 (-7890 5250);
PAINT PINK (-7890 5250);
DISPLAY INVISIBLE (-7890 5250);
FORCEPROP 1 LAST Q_DEPT BU9
J 1
(-3763 49);
DISPLAY 1.957447 (-3763 49);
PAINT GREEN (-3763 49);
DISPLAY INVISIBLE (-3763 49);
FORCEPROP 1 LAST COMMENT_BODY TRUE
J 0
(12 -13);
DISPLAY 0.978723 (12 -13);
PAINT GREEN (12 -13);
DISPLAY INVISIBLE (12 -13);
WIRE 16 -1 (-525 3900)(-525 4025);
WIRE 16 -1 (-525 3275)(-525 3125);
WIRE 16 -1 (-8850 6075)(-8850 6225);
WIRE 16 -1 (-8850 5400)(-8850 5300);
WIRE 16 -1 (-8700 4650)(-8700 4750);
WIRE 16 -1 (-9125 5250)(-9125 5300);
WIRE 16 -1 (-9125 4625)(-9125 4450);
WIRE 16 -1 (-8700 3950)(-8700 3900);
WIRE 16 -1 (-6250 2775)(-6250 2675);
WIRE 16 -1 (-6550 2925)(-6500 2925);
WIRE 16 -1 (-6500 2925)(-6500 2700);
WIRE 16 -1 (-7375 2800)(-7375 2700);
WIRE 16 -1 (-7100 2925)(-7200 2925);
WIRE 16 -1 (-7200 2925)(-7200 2700);
WIRE 16 -1 (-6300 1975)(-6650 1975);
WIRE 16 -1 (-6650 1975)(-6650 2175);
WIRE 16 -1 (-8000 1050)(-8300 1050);
WIRE 16 -1 (-8300 1050)(-8300 1225);
WIRE 16 -1 (-8200 3400)(-8200 3300);
WIRE 16 -1 (-8200 4025)(-8200 4125);
WIRE 16 -1 (-1925 3100)(-1925 3225);
WIRE 16 -1 (-1925 2425)(-1925 2325);
WIRE 16 -1 (-2400 2575)(-2400 2525);
WIRE 16 -1 (-7375 3725)(-5125 3725);
FORCEPROP 2 LAST SIG_NAME XTAL_USB_CPU0_HUB2_XOUT
J 0
(-6085 3750);
DISPLAY 0.680851 (-6085 3750);
FORCEPROP 2 LASTPROP $XRERR UNIQUE?
J 0
(-6325 3750);
DISPLAY 0.638298 (-6325 3750);
PAINT MONO (-6325 3750);
DISPLAY INVISIBLE (-6325 3750);
WIRE 16 -1 (-7375 3725)(-7375 3475);
WIRE 16 -1 (-7025 3475)(-7375 3475);
WIRE 16 -1 (-7375 3475)(-7375 3125);
WIRE 16 -1 (-7100 3125)(-7375 3125);
WIRE 16 -1 (-7375 3000)(-7375 3125);
WIRE 16 -1 (-6825 3475)(-6250 3475);
WIRE 16 -1 (-5125 3475)(-6250 3475);
FORCEPROP 2 LAST SIG_NAME XTAL_USB_CPU0_HUB2_XIN
J 0
(-6085 3500);
DISPLAY 0.680851 (-6085 3500);
FORCEPROP 2 LASTPROP $XRERR UNIQUE?
J 0
(-6325 3500);
DISPLAY 0.638298 (-6325 3500);
PAINT MONO (-6325 3500);
DISPLAY INVISIBLE (-6325 3500);
WIRE 16 -1 (-6250 3475)(-6250 3125);
WIRE 16 -1 (-6250 3125)(-6550 3125);
WIRE 16 -1 (-6250 2975)(-6250 3125);
WIRE 16 -1 (-6025 525)(-6275 525);
WIRE 16 -1 (-5750 525)(-6025 525);
WIRE 16 -1 (-6025 725)(-6025 525);
WIRE 16 -1 (-6275 725)(-6275 525);
WIRE 16 -1 (-6275 525)(-6700 525);
WIRE 16 -1 (-6700 725)(-6700 525);
WIRE 16 -1 (-6700 525)(-7100 525);
WIRE 16 -1 (-5450 525)(-5750 525);
WIRE 16 -1 (-5750 750)(-5750 525);
WIRE 16 -1 (-5175 525)(-5450 525);
WIRE 16 -1 (-5450 725)(-5450 525);
WIRE 16 -1 (-7100 725)(-7100 525);
WIRE 16 -1 (-7100 525)(-7100 450);
WIRE 16 -1 (-4875 525)(-5175 525);
WIRE 16 -1 (-5175 750)(-5175 525);
WIRE 16 -1 (-4550 525)(-4875 525);
WIRE 16 -1 (-4875 750)(-4875 525);
WIRE 16 -1 (-4250 525)(-4550 525);
WIRE 16 -1 (-4550 725)(-4550 525);
WIRE 16 -1 (-3925 525)(-4250 525);
WIRE 16 -1 (-4250 750)(-4250 525);
WIRE 16 -1 (-3675 525)(-3925 525);
WIRE 16 -1 (-3925 750)(-3925 525);
WIRE 16 -1 (-3400 525)(-3675 525);
WIRE 16 -1 (-3675 750)(-3675 525);
WIRE 16 -1 (-3125 525)(-3400 525);
WIRE 16 -1 (-3400 750)(-3400 525);
WIRE 16 -1 (-2750 525)(-3125 525);
WIRE 16 -1 (-3125 725)(-3125 525);
WIRE 16 -1 (-2450 525)(-2750 525);
WIRE 16 -1 (-2750 750)(-2750 525);
WIRE 16 -1 (-2200 525)(-2450 525);
WIRE 16 -1 (-2450 750)(-2450 525);
WIRE 16 -1 (-2200 750)(-2200 525);
WIRE 16 -1 (-7800 1050)(-7100 1050);
WIRE 16 -1 (-7100 1050)(-7100 1100);
WIRE 16 -1 (-7100 1050)(-7100 925);
WIRE 16 -1 (-7100 1100)(-6700 1100);
WIRE 16 -1 (-7100 1100)(-7100 1225);
WIRE 16 -1 (-6700 925)(-6700 1100);
WIRE 16 -1 (-6700 1100)(-6275 1100);
WIRE 16 -1 (-6275 1100)(-6025 1100);
WIRE 16 -1 (-6275 925)(-6275 1100);
WIRE 16 -1 (-6025 1100)(-5750 1100);
WIRE 16 -1 (-6025 925)(-6025 1100);
WIRE 16 -1 (-5450 1100)(-5750 1100);
WIRE 16 -1 (-5750 950)(-5750 1100);
WIRE 16 -1 (-5175 1100)(-5450 1100);
WIRE 16 -1 (-5450 925)(-5450 1100);
WIRE 16 -1 (-4875 1100)(-5175 1100);
WIRE 16 -1 (-5175 950)(-5175 1100);
WIRE 16 -1 (-4550 1100)(-4875 1100);
WIRE 16 -1 (-4875 950)(-4875 1100);
WIRE 16 -1 (-4250 1100)(-4550 1100);
WIRE 16 -1 (-4550 925)(-4550 1100);
WIRE 16 -1 (-3925 1100)(-4250 1100);
WIRE 16 -1 (-4250 950)(-4250 1100);
WIRE 16 -1 (-3675 1100)(-3925 1100);
WIRE 16 -1 (-3925 950)(-3925 1100);
WIRE 16 -1 (-3400 1100)(-3675 1100);
WIRE 16 -1 (-3675 950)(-3675 1100);
WIRE 16 -1 (-3125 1100)(-3400 1100);
WIRE 16 -1 (-3400 950)(-3400 1100);
WIRE 16 -1 (-2750 1100)(-3125 1100);
WIRE 16 -1 (-3125 925)(-3125 1100);
WIRE 16 -1 (-2450 1100)(-2750 1100);
WIRE 16 -1 (-2750 950)(-2750 1100);
WIRE 16 -1 (-2200 1100)(-2450 1100);
WIRE 16 -1 (-2450 950)(-2450 1100);
WIRE 16 -1 (-2200 1100)(-2200 950);
WIRE 16 -1 (-5025 1400)(-4600 1400);
WIRE 16 -1 (-5025 1575)(-5025 1400);
WIRE 16 -1 (-5425 1400)(-5025 1400);
WIRE 16 -1 (-4600 1575)(-4600 1400);
WIRE 16 -1 (-4600 1400)(-4350 1400);
WIRE 16 -1 (-4350 1400)(-4075 1400);
WIRE 16 -1 (-4350 1575)(-4350 1400);
WIRE 16 -1 (-5425 1575)(-5425 1400);
WIRE 16 -1 (-5425 1400)(-5425 1350);
WIRE 16 -1 (-4075 1575)(-4075 1400);
WIRE 16 -1 (-4075 1400)(-3825 1400);
WIRE 16 -1 (-3825 1400)(-3575 1400);
WIRE 16 -1 (-3825 1575)(-3825 1400);
WIRE 16 -1 (-3575 1575)(-3575 1400);
WIRE 16 -1 (-3575 1400)(-3325 1400);
WIRE 16 -1 (-3325 1575)(-3325 1400);
WIRE 16 -1 (-3325 1400)(-3075 1400);
WIRE 16 -1 (-3075 1400)(-2825 1400);
WIRE 16 -1 (-3075 1575)(-3075 1400);
WIRE 16 -1 (-2825 1575)(-2825 1400);
WIRE 16 -1 (-2825 1400)(-2575 1400);
WIRE 16 -1 (-2575 1400)(-2325 1400);
WIRE 16 -1 (-2575 1575)(-2575 1400);
WIRE 16 -1 (-2325 1575)(-2325 1400);
WIRE 16 -1 (-2325 1400)(-2050 1400);
WIRE 16 -1 (-2050 1400)(-2050 1575);
WIRE 16 -1 (-5425 1875)(-5025 1875);
WIRE 16 -1 (-5425 1975)(-5425 1875);
WIRE 16 -1 (-5425 1875)(-5425 1775);
WIRE 16 -1 (-5025 1875)(-4600 1875);
WIRE 16 -1 (-5025 1775)(-5025 1875);
WIRE 16 -1 (-4600 1875)(-4350 1875);
WIRE 16 -1 (-4600 1775)(-4600 1875);
WIRE 16 -1 (-6100 1975)(-5425 1975);
WIRE 16 -1 (-5425 1975)(-5425 2175);
WIRE 16 -1 (-4350 1875)(-4075 1875);
WIRE 16 -1 (-4350 1775)(-4350 1875);
WIRE 16 -1 (-4075 1875)(-3825 1875);
WIRE 16 -1 (-4075 1775)(-4075 1875);
WIRE 16 -1 (-3825 1875)(-3575 1875);
WIRE 16 -1 (-3825 1775)(-3825 1875);
WIRE 16 -1 (-3575 1875)(-3325 1875);
WIRE 16 -1 (-3575 1775)(-3575 1875);
WIRE 16 -1 (-3325 1875)(-3075 1875);
WIRE 16 -1 (-3325 1775)(-3325 1875);
WIRE 16 -1 (-3075 1875)(-2825 1875);
WIRE 16 -1 (-3075 1775)(-3075 1875);
WIRE 16 -1 (-2825 1875)(-2575 1875);
WIRE 16 -1 (-2825 1775)(-2825 1875);
WIRE 16 -1 (-2575 1875)(-2325 1875);
WIRE 16 -1 (-2575 1775)(-2575 1875);
WIRE 16 -1 (-2325 1875)(-2050 1875);
WIRE 16 -1 (-2325 1775)(-2325 1875);
WIRE 16 -1 (-2050 1875)(-2050 1775);
WIRE 16 -1 (-3675 3425)(-2750 3425);
WIRE 16 -1 (-2750 3525)(-2750 3425);
WIRE 16 -1 (-3675 3525)(-2750 3525);
WIRE 16 -1 (-2750 3525)(-2750 3575);
WIRE 16 -1 (-3675 3525)(-3675 3575);
WIRE 16 -1 (-2025 5525)(-1500 5525);
WIRE 16 -1 (-1500 5525)(-1500 5675);
WIRE 16 -1 (-1500 5375)(-1500 5525);
WIRE 16 -1 (-1500 5225)(-1500 5375);
WIRE 16 -1 (-3675 5375)(-1500 5375);
WIRE 16 -1 (-2050 5675)(-1500 5675);
WIRE 16 -1 (-1500 5675)(-1500 5750);
WIRE 16 -1 (-2025 5225)(-1500 5225);
WIRE 16 -1 (-1500 5075)(-1500 5225);
WIRE 16 -1 (-1500 4925)(-1500 5075);
WIRE 16 -1 (-2050 5075)(-1500 5075);
WIRE 16 -1 (-1500 4775)(-1500 4925);
WIRE 16 -1 (-2025 4925)(-1500 4925);
WIRE 16 -1 (-1500 4625)(-1500 4775);
WIRE 16 -1 (-3675 4775)(-1500 4775);
WIRE 16 -1 (-3675 4625)(-1500 4625);
WIRE 16 -1 (-1700 3725)(-1200 3725);
WIRE 16 -1 (-1200 3725)(-1200 3875);
WIRE 16 -1 (-2050 3875)(-1200 3875);
WIRE 16 -1 (-1200 3875)(-1200 4000);
WIRE 16 -1 (-8200 3600)(-8200 3725);
WIRE 16 -1 (-7725 3725)(-8200 3725);
WIRE 16 -1 (-8200 3725)(-8200 3825);
WIRE 16 -1 (-7725 4325)(-7725 3725);
WIRE 16 -1 (-7725 4325)(-5125 4325);
FORCEPROP 2 LAST SIG_NAME USB_HUB2_TI_FULLPWRMGMTZ_MRP_PROG_FUNC3
J 0
(-7210 4350);
DISPLAY 0.680851 (-7210 4350);
FORCEPROP 2 LASTPROP $XRERR UNIQUE?
J 0
(-7450 4350);
DISPLAY 0.638298 (-7450 4350);
PAINT MONO (-7450 4350);
DISPLAY INVISIBLE (-7450 4350);
FORCEPROP 0 LAST $PNN USB_HUB2_TI_FULLPWRMGMTZ_MRP_PR
J 0
(-6460 4392);
DISPLAY INVISIBLE (-6460 4392);
WIRE 16 -1 (-3875 2725)(-3675 2725);
WIRE 16 -1 (-3875 2725)(-3875 2300);
WIRE 16 -1 (-5075 2725)(-3875 2725);
FORCEPROP 2 LAST SIG_NAME USB_HUB2_TI_GANGED_MRP_I2C_SLV_CFG0
J 0
(-5060 2760);
DISPLAY 0.680851 (-5060 2760);
WIRE 16 -1 (-3875 2300)(-3650 2300);
WIRE 16 -1 (-7550 4925)(-9125 4925);
FORCEPROP 2 LAST SIG_NAME USB_HUB2_TI_HS_SUSPEND
J 0
(-8735 4935);
DISPLAY 0.553191 (-8735 4935);
FORCEPROP 2 LASTPROP $XRERR UNIQUE?
J 0
(-8975 4935);
DISPLAY 0.638298 (-8975 4935);
PAINT MONO (-8975 4935);
DISPLAY INVISIBLE (-8975 4935);
WIRE 16 -1 (-9125 4925)(-9125 5050);
WIRE 16 -1 (-9125 4825)(-9125 4925);
WIRE 16 -1 (-3675 5675)(-2250 5675);
FORCEPROP 2 LAST SIG_NAME USB_HUB2_TI_VDD_MRP_USB3DN_TXDM1
J 0
(-3460 5685);
DISPLAY 0.553191 (-3460 5685);
FORCEPROP 2 LASTPROP $XRERR UNIQUE?
J 0
(-3700 5685);
DISPLAY 0.638298 (-3700 5685);
PAINT MONO (-3700 5685);
DISPLAY INVISIBLE (-3700 5685);
WIRE 16 -1 (-6875 5475)(-7750 5475);
FORCEPROP 2 LAST SIG_NAME SMB_USB_CPU0_HUB1_SDA
J 0
(-7685 5485);
DISPLAY 0.680851 (-7685 5485);
WIRE 16 -1 (-6900 5275)(-7775 5275);
FORCEPROP 2 LAST SIG_NAME SMB_USB_CPU0_HUB1_SCL
J 0
(-7760 5285);
DISPLAY 0.680851 (-7760 5285);
WIRE 16 -1 (-7850 4750)(-7850 4350);
WIRE 16 -1 (-7550 4750)(-7850 4750);
WIRE 16 -1 (-7850 4350)(-8700 4350);
FORCEPROP 2 LAST SIG_NAME USB_HUB2_MRP_CFG_NON_REM
J 0
(-8535 4375);
DISPLAY 0.553191 (-8535 4375);
FORCEPROP 2 LASTPROP $XRERR UNIQUE?
J 0
(-8775 4375);
DISPLAY 0.638298 (-8775 4375);
PAINT MONO (-8775 4375);
DISPLAY INVISIBLE (-8775 4375);
WIRE 16 -1 (-8700 4350)(-8700 4450);
WIRE 16 -1 (-8700 4350)(-8700 4150);
WIRE 16 -1 (-2225 5225)(-3675 5225);
FORCEPROP 2 LAST SIG_NAME USB_HUB2_TI_VDD_MRP_USB3DN_TXDP3
J 0
(-3510 5225);
DISPLAY 0.680851 (-3510 5225);
FORCEPROP 2 LASTPROP $XRERR UNIQUE?
J 0
(-3750 5225);
DISPLAY 0.638298 (-3750 5225);
PAINT MONO (-3750 5225);
DISPLAY INVISIBLE (-3750 5225);
FORCEPROP 0 LAST $PNN USB_HUB2_TI_VDD_MRP_USB3DN_TXDP
J 0
(-3035 5267);
DISPLAY INVISIBLE (-3035 5267);
WIRE 16 -1 (-3675 5525)(-2225 5525);
FORCEPROP 2 LAST SIG_NAME USB_HUB2_TI_VDD_MRP_USB3DN_RXDM1
J 0
(-3560 5525);
DISPLAY 0.680851 (-3560 5525);
FORCEPROP 2 LASTPROP $XRERR UNIQUE?
J 0
(-3800 5525);
DISPLAY 0.638298 (-3800 5525);
PAINT MONO (-3800 5525);
DISPLAY INVISIBLE (-3800 5525);
WIRE 16 -1 (-2250 5075)(-3675 5075);
FORCEPROP 2 LAST SIG_NAME USB_HUB2_TI_VDD_MRP_USB3DN_TXDP4
J 0
(-3560 5100);
DISPLAY 0.680851 (-3560 5100);
FORCEPROP 2 LASTPROP $XRERR UNIQUE?
J 0
(-3800 5100);
DISPLAY 0.638298 (-3800 5100);
PAINT MONO (-3800 5100);
DISPLAY INVISIBLE (-3800 5100);
FORCEPROP 0 LAST $PNN USB_HUB2_TI_VDD_MRP_USB3DN_TX_1
J 0
(-3135 5117);
DISPLAY INVISIBLE (-3135 5117);
WIRE 16 -1 (-3675 4925)(-2225 4925);
FORCEPROP 2 LAST SIG_NAME USB_HUB2_TI_VDD_MRP_USB3DN_RXDP4
J 0
(-3510 4935);
DISPLAY 0.680851 (-3510 4935);
FORCEPROP 2 LASTPROP $XRERR UNIQUE?
J 0
(-3750 4935);
DISPLAY 0.638298 (-3750 4935);
PAINT MONO (-3750 4935);
DISPLAY INVISIBLE (-3750 4935);
WIRE 16 -1 (-3675 3875)(-2250 3875);
FORCEPROP 2 LAST SIG_NAME USB_HUB2_TI_VDD33_MRP_PROG_FUNC7
J 0
(-3485 3900);
DISPLAY 0.680851 (-3485 3900);
FORCEPROP 2 LASTPROP $XRERR UNIQUE?
J 0
(-3725 3900);
DISPLAY 0.638298 (-3725 3900);
PAINT MONO (-3725 3900);
DISPLAY INVISIBLE (-3725 3900);
FORCEPROP 0 LAST $PNN USB_HUB2_TI_VDD33_MRP_PROG_FUNC
J 0
(-3485 3917);
DISPLAY INVISIBLE (-3485 3917);
WIRE 16 -1 (-1700 3650)(-525 3650);
FORCEPROP 2 LAST SIG_NAME USB_HUB2_MRP_PRT_CTL4_GANGPWR
J 0
(-1560 3600);
DISPLAY 0.680851 (-1560 3600);
FORCEPROP 2 LASTPROP $XRERR UNIQUE?
J 0
(-1800 3600);
DISPLAY 0.638298 (-1800 3600);
PAINT MONO (-1800 3600);
DISPLAY INVISIBLE (-1800 3600);
WIRE 16 -1 (-525 3650)(-525 3700);
WIRE 16 -1 (-525 3650)(-525 3475);
WIRE 16 -1 (-3675 3725)(-2175 3725);
FORCEPROP 2 LAST SIG_NAME USB_HUB2_TI_VDD33_MRP_PRT_CTL4_GANGPWR
J 0
(-3460 3750);
DISPLAY 0.680851 (-3460 3750);
FORCEPROP 2 LASTPROP $XRERR UNIQUE?
J 0
(-3700 3750);
DISPLAY 0.638298 (-3700 3750);
PAINT MONO (-3700 3750);
DISPLAY INVISIBLE (-3700 3750);
FORCEPROP 0 LAST $PNN USB_HUB2_TI_VDD33_MRP_PRT_CTL4_
J 0
(-3535 3767);
DISPLAY INVISIBLE (-3535 3767);
WIRE 16 -1 (-2175 3725)(-1900 3725);
WIRE 16 -1 (-2175 3725)(-2175 3650);
WIRE 16 -1 (-2175 3650)(-1900 3650);
WIRE 16 -1 (-5125 5475)(-6675 5475);
FORCEPROP 2 LAST SIG_NAME SMB_USB_HUB2_TI_SDA_MRP_PRT_CTL2
J 0
(-6260 5500);
DISPLAY 0.680851 (-6260 5500);
FORCEPROP 2 LASTPROP $XRERR UNIQUE?
J 0
(-6500 5500);
DISPLAY 0.638298 (-6500 5500);
PAINT MONO (-6500 5500);
DISPLAY INVISIBLE (-6500 5500);
WIRE 16 -1 (-5125 5275)(-6700 5275);
FORCEPROP 2 LAST SIG_NAME SMB_USB_HUB2_TI_SCL_MRP_PRT_CTL1
J 0
(-6235 5300);
DISPLAY 0.680851 (-6235 5300);
FORCEPROP 2 LASTPROP $XRERR UNIQUE?
J 0
(-6475 5300);
DISPLAY 0.638298 (-6475 5300);
PAINT MONO (-6475 5300);
DISPLAY INVISIBLE (-6475 5300);
WIRE 16 -1 (-5125 4925)(-6850 4925);
FORCEPROP 2 LAST SIG_NAME USB_HUB2_TI_HS_SUSPEND_MRP_CFG_NON_REM
J 0
(-6260 4950);
DISPLAY 0.553191 (-6260 4950);
FORCEPROP 2 LASTPROP $XRERR UNIQUE?
J 0
(-6500 4950);
DISPLAY 0.638298 (-6500 4950);
PAINT MONO (-6500 4950);
DISPLAY INVISIBLE (-6500 4950);
WIRE 16 -1 (-6850 4750)(-6850 4925);
WIRE 16 -1 (-6850 4925)(-7350 4925);
WIRE 16 -1 (-6850 4750)(-7350 4750);
WIRE 16 -1 (-3475 2725)(-1925 2725);
FORCEPROP 2 LAST SIG_NAME USB_HUB2_TI_GANGED
J 0
(-3185 2750);
DISPLAY 0.680851 (-3185 2750);
FORCEPROP 2 LASTPROP $XRERR UNIQUE?
J 0
(-3425 2750);
DISPLAY 0.638298 (-3425 2750);
PAINT MONO (-3425 2750);
DISPLAY INVISIBLE (-3425 2750);
WIRE 16 -1 (-1925 2900)(-1925 2725);
WIRE 16 -1 (-1925 2725)(-1925 2625);
WIRE 16 -1 (-2400 2300)(-2400 2325);
WIRE 16 -1 (-2400 2300)(-3450 2300);
FORCEPROP 2 LAST SIG_NAME USB_HUB2_MRP_I2C_SLV_CFG0
J 0
(-3335 2325);
DISPLAY 0.680851 (-3335 2325);
FORCEPROP 2 LASTPROP $XRERR UNIQUE?
J 0
(-3575 2325);
DISPLAY 0.638298 (-3575 2325);
PAINT MONO (-3575 2325);
DISPLAY INVISIBLE (-3575 2325);
WIRE 16 -1 (-6800 4625)(-5125 4625);
FORCEPROP 2 LAST SIG_NAME USB_HUB2_TI_GANGED_MRP_I2C_SLV_CFG0
J 0
(-6660 4635);
DISPLAY 0.680851 (-6660 4635);
FORCEPROP 0 LAST $PNN USB_HUB2_TI_GANGED_MRP_I2C_SLV_
J 0
(-6660 4667);
DISPLAY INVISIBLE (-6660 4667);
WIRE 16 -1 (-8850 5600)(-8850 5675);
WIRE 16 -1 (-8850 5675)(-5125 5675);
FORCEPROP 2 LAST SIG_NAME USB_HUB2_TI_SMBUSZ_MRP_PROG_FUNC2
J 0
(-6460 5685);
DISPLAY 0.680851 (-6460 5685);
FORCEPROP 2 LASTPROP $XRERR UNIQUE?
J 0
(-6700 5685);
DISPLAY 0.638298 (-6700 5685);
PAINT MONO (-6700 5685);
DISPLAY INVISIBLE (-6700 5685);
FORCEPROP 0 LAST $PNN USB_HUB2_TI_SMBUSZ_MRP_PROG_FUN
J 0
(-6460 5717);
DISPLAY INVISIBLE (-6460 5717);
WIRE 16 -1 (-8850 5675)(-8850 5875);
DOT 1 (-7375 3125);
DOT 1 (-8850 5675);
DOT 1 (-1925 2725);
DOT 1 (-525 3650);
DOT 1 (-1200 3875);
DOT 1 (-1500 5675);
DOT 1 (-6250 3475);
DOT 1 (-5425 1400);
DOT 1 (-5025 1400);
DOT 1 (-4600 1400);
DOT 1 (-4600 1875);
DOT 1 (-4350 1400);
DOT 1 (-4075 1400);
DOT 1 (-3575 1400);
DOT 1 (-3325 1400);
DOT 1 (-3825 1875);
DOT 1 (-1500 5225);
DOT 1 (-7100 1100);
DOT 1 (-7100 1050);
DOT 1 (-3400 525);
DOT 1 (-2750 525);
DOT 1 (-4550 1100);
DOT 1 (-5750 525);
DOT 1 (-2450 525);
DOT 1 (-2450 1100);
DOT 1 (-3125 525);
DOT 1 (-3675 525);
DOT 1 (-3675 1100);
DOT 1 (-3925 525);
DOT 1 (-4250 525);
DOT 1 (-4250 1100);
DOT 1 (-4550 525);
DOT 1 (-4875 525);
DOT 1 (-4875 1100);
DOT 1 (-5175 525);
DOT 1 (-5450 525);
DOT 1 (-6025 525);
DOT 1 (-6025 1100);
DOT 1 (-6275 525);
DOT 1 (-6700 525);
DOT 1 (-1500 5075);
DOT 1 (-8700 4350);
DOT 1 (-6850 4925);
DOT 1 (-9125 4925);
DOT 1 (-4350 1875);
DOT 1 (-3075 1875);
DOT 1 (-2325 1875);
DOT 1 (-1500 5375);
DOT 1 (-1500 5525);
DOT 1 (-2175 3725);
DOT 1 (-2750 3525);
DOT 1 (-1500 4925);
DOT 1 (-1500 4775);
DOT 1 (-5750 1100);
DOT 1 (-5025 1875);
DOT 1 (-5425 1975);
DOT 1 (-5425 1875);
DOT 1 (-3875 2725);
DOT 1 (-4075 1875);
DOT 1 (-3575 1875);
DOT 1 (-3325 1875);
DOT 1 (-2825 1875);
DOT 1 (-2575 1875);
DOT 1 (-3925 1100);
DOT 1 (-6700 1100);
DOT 1 (-6275 1100);
DOT 1 (-5450 1100);
DOT 1 (-5175 1100);
DOT 1 (-3825 1400);
DOT 1 (-3075 1400);
DOT 1 (-2575 1400);
DOT 1 (-3400 1100);
DOT 1 (-3125 1100);
DOT 1 (-2750 1100);
DOT 1 (-2325 1400);
DOT 1 (-2825 1400);
DOT 1 (-7100 525);
DOT 1 (-7375 3475);
DOT 1 (-8200 3725);
DOT 1 (-6250 3125);
FORCENOTE
MRP=25MHZ
(-7300 2425) 0;
DISPLAY LEFT (-7300 2425);
DISPLAY 1.021277 (-7300 2425);
FORCENOTE
TI=24MHZ
(-7300 2475) 0;
DISPLAY LEFT (-7300 2475);
DISPLAY 1.021277 (-7300 2475);
FORCENOTE
QPN:AL008042000
(-4325 6425) 0;
DISPLAY LEFT (-4325 6425);
DISPLAY 1.276596 (-4325 6425);
FORCENOTE
MFR:MRP
(-2900 6300) 0;
DISPLAY LEFT (-2900 6300);
DISPLAY 1.276596 (-2900 6300);
FORCENOTE
MFR:TI
(-4325 6275) 0;
DISPLAY LEFT (-4325 6275);
DISPLAY 1.276596 (-4325 6275);
FORCENOTE
2ND
(-4325 6525) 0;
DISPLAY LEFT (-4325 6525);
DISPLAY 1.276596 (-4325 6525);
FORCENOTE
QPN:AL005734000
(-2900 6450) 0;
DISPLAY LEFT (-2900 6450);
DISPLAY 1.276596 (-2900 6450);
FORCENOTE
3RD
(-2925 6525) 0;
DISPLAY LEFT (-2925 6525);
DISPLAY 1.276596 (-2925 6525);
FORCENOTE
MFR PN:TUSB8042AIRGCR
(-4325 6350) 0;
DISPLAY LEFT (-4325 6350);
DISPLAY 1.276596 (-4325 6350);
FORCENOTE
MFR PN:USB5734T/M
(-2900 6375) 0;
DISPLAY LEFT (-2900 6375);
DISPLAY 1.276596 (-2900 6375);
FORCENOTE
XTAL:
(-7300 2525) 0;
DISPLAY LEFT (-7300 2525);
DISPLAY 1.021277 (-7300 2525);
QUIT
